(kicad_sch (version 20230121) (generator eeschema)

  (paper "A3")

  (title_block
    (title "D1600E PSU Breakout Board")
    (date "2023-10-18")
    (rev "1.4.3")
    (comment 1 "www.antmicro.com")
    (comment 2 "Antmicro Ltd.")
  )

  (junction (at 99.06 185.42) (diameter 0) (color 0 0 0 0)
  )
  (junction (at 105.41 67.31) (diameter 0) (color 0 0 0 0)
  )
  (junction (at 165.1 152.4) (diameter 0) (color 0 0 0 0)
  )
  (junction (at 44.45 219.71) (diameter 0) (color 0 0 0 0)
  )
  (junction (at 217.17 137.16) (diameter 0) (color 0 0 0 0)
  )
  (junction (at 99.06 162.56) (diameter 0) (color 0 0 0 0)
  )
  (junction (at 99.06 137.16) (diameter 0) (color 0 0 0 0)
  )
  (junction (at 81.28 134.62) (diameter 0) (color 0 0 0 0)
  )
  (junction (at 217.17 142.24) (diameter 0) (color 0 0 0 0)
  )
  (junction (at 45.72 156.21) (diameter 0) (color 0 0 0 0)
  )
  (junction (at 332.74 215.9) (diameter 0) (color 0 0 0 0)
  )
  (junction (at 45.72 135.89) (diameter 0) (color 0 0 0 0)
  )
  (junction (at 63.5 156.21) (diameter 0) (color 0 0 0 0)
  )
  (junction (at 63.5 158.75) (diameter 0) (color 0 0 0 0)
  )
  (junction (at 209.55 88.9) (diameter 0) (color 0 0 0 0)
  )
  (junction (at 45.72 133.35) (diameter 0) (color 0 0 0 0)
  )
  (junction (at 81.28 177.8) (diameter 0) (color 0 0 0 0)
  )
  (junction (at 99.06 134.62) (diameter 0) (color 0 0 0 0)
  )
  (junction (at 185.42 77.47) (diameter 0) (color 0 0 0 0)
  )
  (junction (at 63.5 135.89) (diameter 0) (color 0 0 0 0)
  )
  (junction (at 81.28 160.02) (diameter 0) (color 0 0 0 0)
  )
  (junction (at 81.28 137.16) (diameter 0) (color 0 0 0 0)
  )
  (junction (at 165.1 157.48) (diameter 0) (color 0 0 0 0)
  )
  (junction (at 81.28 182.88) (diameter 0) (color 0 0 0 0)
  )
  (junction (at 217.17 139.7) (diameter 0) (color 0 0 0 0)
  )
  (junction (at 99.06 182.88) (diameter 0) (color 0 0 0 0)
  )
  (junction (at 63.5 138.43) (diameter 0) (color 0 0 0 0)
  )
  (junction (at 45.72 153.67) (diameter 0) (color 0 0 0 0)
  )
  (junction (at 90.17 204.47) (diameter 0) (color 0 0 0 0)
  )
  (junction (at 165.1 154.94) (diameter 0) (color 0 0 0 0)
  )
  (junction (at 99.06 157.48) (diameter 0) (color 0 0 0 0)
  )
  (junction (at 63.5 161.29) (diameter 0) (color 0 0 0 0)
  )
  (junction (at 99.06 160.02) (diameter 0) (color 0 0 0 0)
  )
  (junction (at 217.17 187.96) (diameter 0) (color 0 0 0 0)
  )
  (junction (at 222.25 187.96) (diameter 0) (color 0 0 0 0)
  )
  (junction (at 332.74 222.25) (diameter 0) (color 0 0 0 0)
  )
  (junction (at 99.06 180.34) (diameter 0) (color 0 0 0 0)
  )
  (junction (at 232.41 152.4) (diameter 0) (color 0 0 0 0)
  )
  (junction (at 179.07 137.16) (diameter 0) (color 0 0 0 0)
  )
  (junction (at 332.74 209.55) (diameter 0) (color 0 0 0 0)
  )
  (junction (at 165.1 149.86) (diameter 0) (color 0 0 0 0)
  )
  (junction (at 232.41 149.86) (diameter 0) (color 0 0 0 0)
  )
  (junction (at 99.06 139.7) (diameter 0) (color 0 0 0 0)
  )
  (junction (at 232.41 154.94) (diameter 0) (color 0 0 0 0)
  )
  (junction (at 44.45 204.47) (diameter 0) (color 0 0 0 0)
  )
  (junction (at 91.44 232.41) (diameter 0) (color 0 0 0 0)
  )
  (junction (at 179.07 142.24) (diameter 0) (color 0 0 0 0)
  )
  (junction (at 81.28 180.34) (diameter 0) (color 0 0 0 0)
  )
  (junction (at 81.28 154.94) (diameter 0) (color 0 0 0 0)
  )
  (junction (at 91.44 219.71) (diameter 0) (color 0 0 0 0)
  )
  (junction (at 81.28 132.08) (diameter 0) (color 0 0 0 0)
  )
  (junction (at 81.28 157.48) (diameter 0) (color 0 0 0 0)
  )
  (junction (at 45.72 130.81) (diameter 0) (color 0 0 0 0)
  )
  (junction (at 179.07 139.7) (diameter 0) (color 0 0 0 0)
  )
  (junction (at 105.41 72.39) (diameter 0) (color 0 0 0 0)
  )
  (junction (at 45.72 158.75) (diameter 0) (color 0 0 0 0)
  )
  (junction (at 63.5 133.35) (diameter 0) (color 0 0 0 0)
  )

  (no_connect (at 43.18 80.01))
  (no_connect (at 191.77 80.01))
  (no_connect (at 113.03 80.01))
  (no_connect (at 215.9 157.48))
  (no_connect (at 204.47 74.93))

  (wire (pts (xy 215.9 185.42) (xy 217.17 185.42))
    (stroke (width 0) (type default))
  )
  (wire (pts (xy 44.45 219.71) (xy 44.45 222.25))
    (stroke (width 0) (type default))
  )
  (wire (pts (xy 179.07 139.7) (xy 180.34 139.7))
    (stroke (width 0) (type default))
  )
  (wire (pts (xy 165.1 149.86) (xy 165.1 152.4))
    (stroke (width 0) (type default))
  )
  (wire (pts (xy 105.41 64.77) (xy 105.41 67.31))
    (stroke (width 0) (type default))
  )
  (wire (pts (xy 90.17 204.47) (xy 90.17 207.01))
    (stroke (width 0) (type default))
  )
  (wire (pts (xy 179.07 137.16) (xy 179.07 139.7))
    (stroke (width 0) (type default))
  )
  (wire (pts (xy 165.1 257.81) (xy 165.1 260.35))
    (stroke (width 0) (type default))
  )
  (wire (pts (xy 48.26 158.75) (xy 45.72 158.75))
    (stroke (width 0) (type default))
  )
  (wire (pts (xy 83.82 134.62) (xy 81.28 134.62))
    (stroke (width 0) (type default))
  )
  (wire (pts (xy 81.28 157.48) (xy 81.28 160.02))
    (stroke (width 0) (type default))
  )
  (wire (pts (xy 96.52 180.34) (xy 99.06 180.34))
    (stroke (width 0) (type default))
  )
  (wire (pts (xy 60.96 161.29) (xy 63.5 161.29))
    (stroke (width 0) (type default))
  )
  (polyline (pts (xy 260.35 262.89) (xy 294.64 262.89))
    (stroke (width 0) (type dash))
  )

  (wire (pts (xy 222.25 80.01) (xy 222.25 83.82))
    (stroke (width 0) (type default))
  )
  (wire (pts (xy 215.9 162.56) (xy 217.17 162.56))
    (stroke (width 0) (type default))
  )
  (wire (pts (xy 215.9 167.64) (xy 217.17 167.64))
    (stroke (width 0) (type default))
  )
  (wire (pts (xy 217.17 187.96) (xy 217.17 190.5))
    (stroke (width 0) (type default))
  )
  (wire (pts (xy 90.17 72.39) (xy 93.98 72.39))
    (stroke (width 0) (type default))
  )
  (wire (pts (xy 96.52 182.88) (xy 99.06 182.88))
    (stroke (width 0) (type default))
  )
  (wire (pts (xy 83.82 157.48) (xy 81.28 157.48))
    (stroke (width 0) (type default))
  )
  (wire (pts (xy 215.9 139.7) (xy 217.17 139.7))
    (stroke (width 0) (type default))
  )
  (wire (pts (xy 93.98 222.25) (xy 91.44 222.25))
    (stroke (width 0) (type default))
  )
  (wire (pts (xy 215.9 165.1) (xy 217.17 165.1))
    (stroke (width 0) (type default))
  )
  (wire (pts (xy 217.17 142.24) (xy 217.17 144.78))
    (stroke (width 0) (type default))
  )
  (wire (pts (xy 99.06 157.48) (xy 99.06 160.02))
    (stroke (width 0) (type default))
  )
  (wire (pts (xy 105.41 67.31) (xy 105.41 72.39))
    (stroke (width 0) (type default))
  )
  (wire (pts (xy 81.28 139.7) (xy 81.28 137.16))
    (stroke (width 0) (type default))
  )
  (wire (pts (xy 96.52 160.02) (xy 99.06 160.02))
    (stroke (width 0) (type default))
  )
  (wire (pts (xy 99.06 180.34) (xy 99.06 182.88))
    (stroke (width 0) (type default))
  )
  (wire (pts (xy 179.07 185.42) (xy 180.34 185.42))
    (stroke (width 0) (type default))
  )
  (wire (pts (xy 81.28 160.02) (xy 81.28 162.56))
    (stroke (width 0) (type default))
  )
  (wire (pts (xy 217.17 187.96) (xy 222.25 187.96))
    (stroke (width 0) (type default))
  )
  (wire (pts (xy 90.17 204.47) (xy 93.98 204.47))
    (stroke (width 0) (type default))
  )
  (wire (pts (xy 36.83 101.6) (xy 36.83 102.87))
    (stroke (width 0) (type default))
  )
  (wire (pts (xy 179.07 170.18) (xy 180.34 170.18))
    (stroke (width 0) (type default))
  )
  (wire (pts (xy 81.28 185.42) (xy 83.82 185.42))
    (stroke (width 0) (type default))
  )
  (wire (pts (xy 165.1 147.32) (xy 180.34 147.32))
    (stroke (width 0) (type default))
  )
  (wire (pts (xy 46.99 207.01) (xy 44.45 207.01))
    (stroke (width 0) (type default))
  )
  (wire (pts (xy 39.37 74.93) (xy 43.18 74.93))
    (stroke (width 0) (type default))
  )
  (wire (pts (xy 45.72 135.89) (xy 48.26 135.89))
    (stroke (width 0) (type default))
  )
  (wire (pts (xy 109.22 54.61) (xy 109.22 59.69))
    (stroke (width 0) (type default))
  )
  (wire (pts (xy 48.26 138.43) (xy 45.72 138.43))
    (stroke (width 0) (type default))
  )
  (wire (pts (xy 179.07 187.96) (xy 180.34 187.96))
    (stroke (width 0) (type default))
  )
  (wire (pts (xy 179.07 175.26) (xy 180.34 175.26))
    (stroke (width 0) (type default))
  )
  (wire (pts (xy 44.45 204.47) (xy 46.99 204.47))
    (stroke (width 0) (type default))
  )
  (wire (pts (xy 99.06 64.77) (xy 105.41 64.77))
    (stroke (width 0) (type default))
  )
  (wire (pts (xy 45.72 130.81) (xy 41.91 130.81))
    (stroke (width 0) (type default))
  )
  (wire (pts (xy 177.8 242.57) (xy 177.8 245.11))
    (stroke (width 0) (type default))
  )
  (wire (pts (xy 77.47 204.47) (xy 77.47 207.01))
    (stroke (width 0) (type default))
  )
  (wire (pts (xy 217.17 137.16) (xy 217.17 139.7))
    (stroke (width 0) (type default))
  )
  (wire (pts (xy 215.9 154.94) (xy 232.41 154.94))
    (stroke (width 0) (type default))
  )
  (wire (pts (xy 232.41 154.94) (xy 232.41 158.75))
    (stroke (width 0) (type default))
  )
  (wire (pts (xy 152.4 242.57) (xy 152.4 245.11))
    (stroke (width 0) (type default))
  )
  (wire (pts (xy 39.37 72.39) (xy 43.18 72.39))
    (stroke (width 0) (type default))
  )
  (wire (pts (xy 81.28 162.56) (xy 83.82 162.56))
    (stroke (width 0) (type default))
  )
  (wire (pts (xy 215.9 257.81) (xy 215.9 260.35))
    (stroke (width 0) (type default))
  )
  (wire (pts (xy 332.74 209.55) (xy 332.74 215.9))
    (stroke (width 0) (type default))
  )
  (wire (pts (xy 45.72 153.67) (xy 48.26 153.67))
    (stroke (width 0) (type default))
  )
  (polyline (pts (xy 260.35 252.73) (xy 294.64 252.73))
    (stroke (width 0) (type dash))
  )

  (wire (pts (xy 179.07 190.5) (xy 180.34 190.5))
    (stroke (width 0) (type default))
  )
  (wire (pts (xy 81.28 177.8) (xy 77.47 177.8))
    (stroke (width 0) (type default))
  )
  (wire (pts (xy 88.9 64.77) (xy 93.98 64.77))
    (stroke (width 0) (type default))
  )
  (wire (pts (xy 179.07 162.56) (xy 180.34 162.56))
    (stroke (width 0) (type default))
  )
  (wire (pts (xy 81.28 132.08) (xy 77.47 132.08))
    (stroke (width 0) (type default))
  )
  (polyline (pts (xy 260.35 270.51) (xy 294.64 270.51))
    (stroke (width 0) (type dash))
  )

  (wire (pts (xy 190.5 257.81) (xy 190.5 260.35))
    (stroke (width 0) (type default))
  )
  (wire (pts (xy 227.33 250.19) (xy 227.33 252.73))
    (stroke (width 0) (type default))
  )
  (wire (pts (xy 203.2 257.81) (xy 203.2 260.35))
    (stroke (width 0) (type default))
  )
  (wire (pts (xy 165.1 158.75) (xy 165.1 157.48))
    (stroke (width 0) (type default))
  )
  (wire (pts (xy 45.72 138.43) (xy 45.72 135.89))
    (stroke (width 0) (type default))
  )
  (wire (pts (xy 217.17 177.8) (xy 215.9 177.8))
    (stroke (width 0) (type default))
  )
  (wire (pts (xy 44.45 201.93) (xy 46.99 201.93))
    (stroke (width 0) (type default))
  )
  (wire (pts (xy 96.52 132.08) (xy 99.06 132.08))
    (stroke (width 0) (type default))
  )
  (wire (pts (xy 30.48 204.47) (xy 30.48 207.01))
    (stroke (width 0) (type default))
  )
  (wire (pts (xy 105.41 101.6) (xy 102.87 101.6))
    (stroke (width 0) (type default))
  )
  (wire (pts (xy 91.44 219.71) (xy 93.98 219.71))
    (stroke (width 0) (type default))
  )
  (wire (pts (xy 179.07 137.16) (xy 180.34 137.16))
    (stroke (width 0) (type default))
  )
  (wire (pts (xy 179.07 177.8) (xy 180.34 177.8))
    (stroke (width 0) (type default))
  )
  (wire (pts (xy 179.07 180.34) (xy 180.34 180.34))
    (stroke (width 0) (type default))
  )
  (wire (pts (xy 44.45 224.79) (xy 46.99 224.79))
    (stroke (width 0) (type default))
  )
  (wire (pts (xy 60.96 135.89) (xy 63.5 135.89))
    (stroke (width 0) (type default))
  )
  (wire (pts (xy 102.87 96.52) (xy 105.41 96.52))
    (stroke (width 0) (type default))
  )
  (wire (pts (xy 99.06 160.02) (xy 99.06 162.56))
    (stroke (width 0) (type default))
  )
  (wire (pts (xy 215.9 180.34) (xy 217.17 180.34))
    (stroke (width 0) (type default))
  )
  (wire (pts (xy 215.9 182.88) (xy 217.17 182.88))
    (stroke (width 0) (type default))
  )
  (wire (pts (xy 48.26 133.35) (xy 45.72 133.35))
    (stroke (width 0) (type default))
  )
  (wire (pts (xy 177.8 250.19) (xy 177.8 252.73))
    (stroke (width 0) (type default))
  )
  (wire (pts (xy 222.25 189.23) (xy 222.25 187.96))
    (stroke (width 0) (type default))
  )
  (wire (pts (xy 165.1 157.48) (xy 165.1 154.94))
    (stroke (width 0) (type default))
  )
  (wire (pts (xy 45.72 156.21) (xy 45.72 153.67))
    (stroke (width 0) (type default))
  )
  (wire (pts (xy 91.44 237.49) (xy 93.98 237.49))
    (stroke (width 0) (type default))
  )
  (wire (pts (xy 48.26 156.21) (xy 45.72 156.21))
    (stroke (width 0) (type default))
  )
  (wire (pts (xy 179.07 167.64) (xy 180.34 167.64))
    (stroke (width 0) (type default))
  )
  (wire (pts (xy 203.2 250.19) (xy 203.2 252.73))
    (stroke (width 0) (type default))
  )
  (wire (pts (xy 91.44 201.93) (xy 93.98 201.93))
    (stroke (width 0) (type default))
  )
  (wire (pts (xy 99.06 185.42) (xy 99.06 187.96))
    (stroke (width 0) (type default))
  )
  (wire (pts (xy 99.06 137.16) (xy 99.06 139.7))
    (stroke (width 0) (type default))
  )
  (wire (pts (xy 109.22 80.01) (xy 109.22 77.47))
    (stroke (width 0) (type default))
  )
  (wire (pts (xy 88.9 67.31) (xy 105.41 67.31))
    (stroke (width 0) (type default))
  )
  (wire (pts (xy 165.1 147.32) (xy 165.1 149.86))
    (stroke (width 0) (type default))
  )
  (wire (pts (xy 185.42 67.31) (xy 203.2 67.31))
    (stroke (width 0) (type default))
  )
  (wire (pts (xy 232.41 149.86) (xy 232.41 152.4))
    (stroke (width 0) (type default))
  )
  (wire (pts (xy 238.76 242.57) (xy 238.76 245.11))
    (stroke (width 0) (type default))
  )
  (wire (pts (xy 185.42 67.31) (xy 185.42 77.47))
    (stroke (width 0) (type default))
  )
  (wire (pts (xy 96.52 154.94) (xy 99.06 154.94))
    (stroke (width 0) (type default))
  )
  (wire (pts (xy 185.42 88.9) (xy 196.85 88.9))
    (stroke (width 0) (type default))
  )
  (wire (pts (xy 81.28 132.08) (xy 83.82 132.08))
    (stroke (width 0) (type default))
  )
  (wire (pts (xy 77.47 204.47) (xy 90.17 204.47))
    (stroke (width 0) (type default))
  )
  (wire (pts (xy 215.9 137.16) (xy 217.17 137.16))
    (stroke (width 0) (type default))
  )
  (wire (pts (xy 91.44 209.55) (xy 93.98 209.55))
    (stroke (width 0) (type default))
  )
  (wire (pts (xy 36.83 96.52) (xy 39.37 96.52))
    (stroke (width 0) (type default))
  )
  (wire (pts (xy 60.96 158.75) (xy 63.5 158.75))
    (stroke (width 0) (type default))
  )
  (wire (pts (xy 44.45 217.17) (xy 46.99 217.17))
    (stroke (width 0) (type default))
  )
  (wire (pts (xy 152.4 250.19) (xy 152.4 252.73))
    (stroke (width 0) (type default))
  )
  (wire (pts (xy 332.74 222.25) (xy 335.28 222.25))
    (stroke (width 0) (type default))
  )
  (wire (pts (xy 63.5 156.21) (xy 63.5 158.75))
    (stroke (width 0) (type default))
  )
  (wire (pts (xy 77.47 232.41) (xy 91.44 232.41))
    (stroke (width 0) (type default))
  )
  (wire (pts (xy 99.06 177.8) (xy 99.06 180.34))
    (stroke (width 0) (type default))
  )
  (wire (pts (xy 83.82 154.94) (xy 81.28 154.94))
    (stroke (width 0) (type default))
  )
  (wire (pts (xy 83.82 160.02) (xy 81.28 160.02))
    (stroke (width 0) (type default))
  )
  (wire (pts (xy 96.52 137.16) (xy 99.06 137.16))
    (stroke (width 0) (type default))
  )
  (wire (pts (xy 173.99 137.16) (xy 179.07 137.16))
    (stroke (width 0) (type default))
  )
  (wire (pts (xy 60.96 138.43) (xy 63.5 138.43))
    (stroke (width 0) (type default))
  )
  (wire (pts (xy 113.03 77.47) (xy 109.22 77.47))
    (stroke (width 0) (type default))
  )
  (wire (pts (xy 30.48 219.71) (xy 44.45 219.71))
    (stroke (width 0) (type default))
  )
  (wire (pts (xy 81.28 182.88) (xy 83.82 182.88))
    (stroke (width 0) (type default))
  )
  (wire (pts (xy 232.41 152.4) (xy 232.41 154.94))
    (stroke (width 0) (type default))
  )
  (wire (pts (xy 63.5 153.67) (xy 63.5 156.21))
    (stroke (width 0) (type default))
  )
  (wire (pts (xy 179.07 142.24) (xy 180.34 142.24))
    (stroke (width 0) (type default))
  )
  (wire (pts (xy 215.9 187.96) (xy 217.17 187.96))
    (stroke (width 0) (type default))
  )
  (wire (pts (xy 179.07 182.88) (xy 180.34 182.88))
    (stroke (width 0) (type default))
  )
  (wire (pts (xy 96.52 177.8) (xy 99.06 177.8))
    (stroke (width 0) (type default))
  )
  (wire (pts (xy 209.55 88.9) (xy 209.55 92.71))
    (stroke (width 0) (type default))
  )
  (wire (pts (xy 105.41 72.39) (xy 113.03 72.39))
    (stroke (width 0) (type default))
  )
  (wire (pts (xy 81.28 154.94) (xy 81.28 157.48))
    (stroke (width 0) (type default))
  )
  (wire (pts (xy 96.52 139.7) (xy 99.06 139.7))
    (stroke (width 0) (type default))
  )
  (wire (pts (xy 332.74 203.2) (xy 335.28 203.2))
    (stroke (width 0) (type default))
  )
  (wire (pts (xy 63.5 133.35) (xy 63.5 135.89))
    (stroke (width 0) (type default))
  )
  (polyline (pts (xy 260.35 255.27) (xy 294.64 255.27))
    (stroke (width 0) (type dash))
  )

  (wire (pts (xy 222.25 187.96) (xy 226.06 187.96))
    (stroke (width 0) (type default))
  )
  (wire (pts (xy 165.1 154.94) (xy 180.34 154.94))
    (stroke (width 0) (type default))
  )
  (wire (pts (xy 63.5 138.43) (xy 63.5 140.97))
    (stroke (width 0) (type default))
  )
  (wire (pts (xy 81.28 134.62) (xy 81.28 137.16))
    (stroke (width 0) (type default))
  )
  (wire (pts (xy 39.37 64.77) (xy 39.37 69.85))
    (stroke (width 0) (type default))
  )
  (wire (pts (xy 177.8 257.81) (xy 177.8 260.35))
    (stroke (width 0) (type default))
  )
  (wire (pts (xy 102.87 99.06) (xy 105.41 99.06))
    (stroke (width 0) (type default))
  )
  (wire (pts (xy 96.52 185.42) (xy 99.06 185.42))
    (stroke (width 0) (type default))
  )
  (wire (pts (xy 45.72 133.35) (xy 45.72 130.81))
    (stroke (width 0) (type default))
  )
  (wire (pts (xy 201.93 88.9) (xy 209.55 88.9))
    (stroke (width 0) (type default))
  )
  (wire (pts (xy 217.17 139.7) (xy 217.17 142.24))
    (stroke (width 0) (type default))
  )
  (wire (pts (xy 81.28 177.8) (xy 83.82 177.8))
    (stroke (width 0) (type default))
  )
  (wire (pts (xy 99.06 132.08) (xy 99.06 134.62))
    (stroke (width 0) (type default))
  )
  (wire (pts (xy 45.72 130.81) (xy 48.26 130.81))
    (stroke (width 0) (type default))
  )
  (wire (pts (xy 39.37 69.85) (xy 43.18 69.85))
    (stroke (width 0) (type default))
  )
  (wire (pts (xy 109.22 64.77) (xy 109.22 69.85))
    (stroke (width 0) (type default))
  )
  (wire (pts (xy 165.1 154.94) (xy 165.1 152.4))
    (stroke (width 0) (type default))
  )
  (polyline (pts (xy 260.35 250.19) (xy 294.64 250.19))
    (stroke (width 0) (type dash))
  )

  (wire (pts (xy 215.9 170.18) (xy 217.17 170.18))
    (stroke (width 0) (type default))
  )
  (wire (pts (xy 99.06 139.7) (xy 99.06 142.24))
    (stroke (width 0) (type default))
  )
  (wire (pts (xy 63.5 158.75) (xy 63.5 161.29))
    (stroke (width 0) (type default))
  )
  (polyline (pts (xy 271.78 247.65) (xy 271.78 280.67))
    (stroke (width 0) (type dash))
  )

  (wire (pts (xy 204.47 80.01) (xy 209.55 80.01))
    (stroke (width 0) (type default))
  )
  (wire (pts (xy 99.06 154.94) (xy 99.06 157.48))
    (stroke (width 0) (type default))
  )
  (wire (pts (xy 60.96 156.21) (xy 63.5 156.21))
    (stroke (width 0) (type default))
  )
  (wire (pts (xy 332.74 215.9) (xy 332.74 222.25))
    (stroke (width 0) (type default))
  )
  (wire (pts (xy 332.74 215.9) (xy 335.28 215.9))
    (stroke (width 0) (type default))
  )
  (wire (pts (xy 203.2 242.57) (xy 203.2 245.11))
    (stroke (width 0) (type default))
  )
  (wire (pts (xy 222.25 55.88) (xy 222.25 62.23))
    (stroke (width 0) (type default))
  )
  (wire (pts (xy 165.1 149.86) (xy 180.34 149.86))
    (stroke (width 0) (type default))
  )
  (wire (pts (xy 99.06 134.62) (xy 99.06 137.16))
    (stroke (width 0) (type default))
  )
  (wire (pts (xy 91.44 219.71) (xy 91.44 222.25))
    (stroke (width 0) (type default))
  )
  (wire (pts (xy 217.17 185.42) (xy 217.17 187.96))
    (stroke (width 0) (type default))
  )
  (polyline (pts (xy 260.35 267.97) (xy 294.64 267.97))
    (stroke (width 0) (type dash))
  )

  (wire (pts (xy 93.98 234.95) (xy 91.44 234.95))
    (stroke (width 0) (type default))
  )
  (wire (pts (xy 179.07 144.78) (xy 179.07 142.24))
    (stroke (width 0) (type default))
  )
  (wire (pts (xy 185.42 77.47) (xy 191.77 77.47))
    (stroke (width 0) (type default))
  )
  (wire (pts (xy 222.25 88.9) (xy 222.25 92.71))
    (stroke (width 0) (type default))
  )
  (wire (pts (xy 215.9 149.86) (xy 232.41 149.86))
    (stroke (width 0) (type default))
  )
  (wire (pts (xy 44.45 209.55) (xy 46.99 209.55))
    (stroke (width 0) (type default))
  )
  (wire (pts (xy 60.96 130.81) (xy 63.5 130.81))
    (stroke (width 0) (type default))
  )
  (wire (pts (xy 60.96 153.67) (xy 63.5 153.67))
    (stroke (width 0) (type default))
  )
  (wire (pts (xy 332.74 209.55) (xy 335.28 209.55))
    (stroke (width 0) (type default))
  )
  (wire (pts (xy 39.37 80.01) (xy 39.37 77.47))
    (stroke (width 0) (type default))
  )
  (wire (pts (xy 332.74 222.25) (xy 332.74 226.06))
    (stroke (width 0) (type default))
  )
  (wire (pts (xy 227.33 257.81) (xy 227.33 260.35))
    (stroke (width 0) (type default))
  )
  (wire (pts (xy 208.28 67.31) (xy 215.9 67.31))
    (stroke (width 0) (type default))
  )
  (wire (pts (xy 99.06 72.39) (xy 105.41 72.39))
    (stroke (width 0) (type default))
  )
  (wire (pts (xy 179.07 165.1) (xy 180.34 165.1))
    (stroke (width 0) (type default))
  )
  (wire (pts (xy 83.82 139.7) (xy 81.28 139.7))
    (stroke (width 0) (type default))
  )
  (wire (pts (xy 179.07 142.24) (xy 179.07 139.7))
    (stroke (width 0) (type default))
  )
  (wire (pts (xy 39.37 54.61) (xy 39.37 59.69))
    (stroke (width 0) (type default))
  )
  (wire (pts (xy 185.42 88.9) (xy 185.42 77.47))
    (stroke (width 0) (type default))
  )
  (wire (pts (xy 81.28 134.62) (xy 81.28 132.08))
    (stroke (width 0) (type default))
  )
  (wire (pts (xy 44.45 204.47) (xy 44.45 207.01))
    (stroke (width 0) (type default))
  )
  (wire (pts (xy 91.44 217.17) (xy 93.98 217.17))
    (stroke (width 0) (type default))
  )
  (wire (pts (xy 165.1 152.4) (xy 180.34 152.4))
    (stroke (width 0) (type default))
  )
  (wire (pts (xy 217.17 137.16) (xy 222.25 137.16))
    (stroke (width 0) (type default))
  )
  (wire (pts (xy 81.28 180.34) (xy 81.28 182.88))
    (stroke (width 0) (type default))
  )
  (wire (pts (xy 83.82 137.16) (xy 81.28 137.16))
    (stroke (width 0) (type default))
  )
  (wire (pts (xy 165.1 242.57) (xy 165.1 245.11))
    (stroke (width 0) (type default))
  )
  (polyline (pts (xy 260.35 278.13) (xy 294.64 278.13))
    (stroke (width 0) (type dash))
  )

  (wire (pts (xy 48.26 161.29) (xy 45.72 161.29))
    (stroke (width 0) (type default))
  )
  (wire (pts (xy 217.17 172.72) (xy 215.9 172.72))
    (stroke (width 0) (type default))
  )
  (wire (pts (xy 81.28 177.8) (xy 81.28 180.34))
    (stroke (width 0) (type default))
  )
  (wire (pts (xy 152.4 257.81) (xy 152.4 260.35))
    (stroke (width 0) (type default))
  )
  (wire (pts (xy 99.06 162.56) (xy 99.06 165.1))
    (stroke (width 0) (type default))
  )
  (wire (pts (xy 222.25 72.39) (xy 222.25 74.93))
    (stroke (width 0) (type default))
  )
  (wire (pts (xy 91.44 232.41) (xy 91.44 234.95))
    (stroke (width 0) (type default))
  )
  (wire (pts (xy 179.07 144.78) (xy 180.34 144.78))
    (stroke (width 0) (type default))
  )
  (wire (pts (xy 77.47 219.71) (xy 91.44 219.71))
    (stroke (width 0) (type default))
  )
  (wire (pts (xy 182.88 77.47) (xy 185.42 77.47))
    (stroke (width 0) (type default))
  )
  (wire (pts (xy 215.9 144.78) (xy 217.17 144.78))
    (stroke (width 0) (type default))
  )
  (wire (pts (xy 215.9 142.24) (xy 217.17 142.24))
    (stroke (width 0) (type default))
  )
  (wire (pts (xy 77.47 232.41) (xy 77.47 234.95))
    (stroke (width 0) (type default))
  )
  (wire (pts (xy 232.41 147.32) (xy 232.41 149.86))
    (stroke (width 0) (type default))
  )
  (wire (pts (xy 44.45 219.71) (xy 46.99 219.71))
    (stroke (width 0) (type default))
  )
  (wire (pts (xy 46.99 222.25) (xy 44.45 222.25))
    (stroke (width 0) (type default))
  )
  (wire (pts (xy 36.83 99.06) (xy 39.37 99.06))
    (stroke (width 0) (type default))
  )
  (wire (pts (xy 190.5 250.19) (xy 190.5 252.73))
    (stroke (width 0) (type default))
  )
  (wire (pts (xy 215.9 147.32) (xy 232.41 147.32))
    (stroke (width 0) (type default))
  )
  (wire (pts (xy 215.9 152.4) (xy 232.41 152.4))
    (stroke (width 0) (type default))
  )
  (polyline (pts (xy 260.35 265.43) (xy 294.64 265.43))
    (stroke (width 0) (type dash))
  )
  (polyline (pts (xy 260.35 273.05) (xy 294.64 273.05))
    (stroke (width 0) (type dash))
  )

  (wire (pts (xy 96.52 157.48) (xy 99.06 157.48))
    (stroke (width 0) (type default))
  )
  (wire (pts (xy 238.76 257.81) (xy 238.76 260.35))
    (stroke (width 0) (type default))
  )
  (wire (pts (xy 45.72 156.21) (xy 45.72 158.75))
    (stroke (width 0) (type default))
  )
  (wire (pts (xy 60.96 133.35) (xy 63.5 133.35))
    (stroke (width 0) (type default))
  )
  (wire (pts (xy 45.72 153.67) (xy 41.91 153.67))
    (stroke (width 0) (type default))
  )
  (wire (pts (xy 81.28 182.88) (xy 81.28 185.42))
    (stroke (width 0) (type default))
  )
  (wire (pts (xy 215.9 250.19) (xy 215.9 252.73))
    (stroke (width 0) (type default))
  )
  (polyline (pts (xy 260.35 260.35) (xy 294.64 260.35))
    (stroke (width 0) (type dash))
  )

  (wire (pts (xy 96.52 162.56) (xy 99.06 162.56))
    (stroke (width 0) (type default))
  )
  (wire (pts (xy 90.17 207.01) (xy 93.98 207.01))
    (stroke (width 0) (type default))
  )
  (wire (pts (xy 190.5 242.57) (xy 190.5 245.11))
    (stroke (width 0) (type default))
  )
  (wire (pts (xy 165.1 250.19) (xy 165.1 252.73))
    (stroke (width 0) (type default))
  )
  (wire (pts (xy 99.06 182.88) (xy 99.06 185.42))
    (stroke (width 0) (type default))
  )
  (wire (pts (xy 217.17 190.5) (xy 215.9 190.5))
    (stroke (width 0) (type default))
  )
  (wire (pts (xy 238.76 250.19) (xy 238.76 252.73))
    (stroke (width 0) (type default))
  )
  (wire (pts (xy 63.5 130.81) (xy 63.5 133.35))
    (stroke (width 0) (type default))
  )
  (wire (pts (xy 113.03 74.93) (xy 90.17 74.93))
    (stroke (width 0) (type default))
  )
  (wire (pts (xy 81.28 154.94) (xy 77.47 154.94))
    (stroke (width 0) (type default))
  )
  (wire (pts (xy 83.82 180.34) (xy 81.28 180.34))
    (stroke (width 0) (type default))
  )
  (wire (pts (xy 30.48 219.71) (xy 30.48 222.25))
    (stroke (width 0) (type default))
  )
  (wire (pts (xy 91.44 232.41) (xy 93.98 232.41))
    (stroke (width 0) (type default))
  )
  (polyline (pts (xy 260.35 275.59) (xy 294.64 275.59))
    (stroke (width 0) (type dash))
  )
  (polyline (pts (xy 283.21 247.65) (xy 283.21 280.67))
    (stroke (width 0) (type dash))
  )

  (wire (pts (xy 209.55 80.01) (xy 209.55 88.9))
    (stroke (width 0) (type default))
  )
  (wire (pts (xy 39.37 77.47) (xy 43.18 77.47))
    (stroke (width 0) (type default))
  )
  (wire (pts (xy 30.48 204.47) (xy 44.45 204.47))
    (stroke (width 0) (type default))
  )
  (polyline (pts (xy 260.35 257.81) (xy 294.64 257.81))
    (stroke (width 0) (type dash))
  )

  (wire (pts (xy 91.44 229.87) (xy 93.98 229.87))
    (stroke (width 0) (type default))
  )
  (wire (pts (xy 102.87 101.6) (xy 102.87 102.87))
    (stroke (width 0) (type default))
  )
  (wire (pts (xy 96.52 134.62) (xy 99.06 134.62))
    (stroke (width 0) (type default))
  )
  (wire (pts (xy 332.74 203.2) (xy 332.74 209.55))
    (stroke (width 0) (type default))
  )
  (wire (pts (xy 77.47 219.71) (xy 77.47 222.25))
    (stroke (width 0) (type default))
  )
  (wire (pts (xy 165.1 157.48) (xy 180.34 157.48))
    (stroke (width 0) (type default))
  )
  (wire (pts (xy 109.22 69.85) (xy 113.03 69.85))
    (stroke (width 0) (type default))
  )
  (wire (pts (xy 179.07 172.72) (xy 180.34 172.72))
    (stroke (width 0) (type default))
  )
  (wire (pts (xy 63.5 161.29) (xy 63.5 163.83))
    (stroke (width 0) (type default))
  )
  (wire (pts (xy 91.44 224.79) (xy 93.98 224.79))
    (stroke (width 0) (type default))
  )
  (wire (pts (xy 63.5 135.89) (xy 63.5 138.43))
    (stroke (width 0) (type default))
  )
  (wire (pts (xy 45.72 133.35) (xy 45.72 135.89))
    (stroke (width 0) (type default))
  )
  (wire (pts (xy 39.37 101.6) (xy 36.83 101.6))
    (stroke (width 0) (type default))
  )
  (wire (pts (xy 227.33 242.57) (xy 227.33 245.11))
    (stroke (width 0) (type default))
  )
  (wire (pts (xy 45.72 161.29) (xy 45.72 158.75))
    (stroke (width 0) (type default))
  )
  (wire (pts (xy 215.9 242.57) (xy 215.9 245.11))
    (stroke (width 0) (type default))
  )
  (wire (pts (xy 215.9 175.26) (xy 217.17 175.26))
    (stroke (width 0) (type default))
  )

  (rectangle (start 25.4 41.91) (end 146.05 109.22)
    (stroke (width 0) (type default))
    (fill (type none))
  )
  (rectangle (start 25.4 120.65) (end 124.46 243.84)
    (stroke (width 0) (type default))
    (fill (type none))
  )
  (rectangle (start 160.02 127) (end 240.03 212.09)
    (stroke (width 0) (type default))
    (fill (type none))
  )
  (rectangle (start 147.32 228.6) (end 246.38 269.24)
    (stroke (width 0) (type default))
    (fill (type none))
  )
  (rectangle (start 166.37 41.91) (end 241.3 110.49)
    (stroke (width 0) (type default))
    (fill (type none))
  )

  (text "Populated" (at 272.796 262.636 0)
    (effects (font (size 1.27 1.27)) (justify left bottom))
  )
  (text "DNP\n" (at 287.02 280.416 0)
    (effects (font (size 1.27 1.27)) (justify left bottom))
  )
  (text "Populated" (at 272.796 260.096 0)
    (effects (font (size 1.27 1.27)) (justify left bottom))
  )
  (text "DNP\n" (at 287.02 275.336 0)
    (effects (font (size 1.27 1.27)) (justify left bottom))
  )
  (text "Y1" (at 264.795 275.336 0)
    (effects (font (size 1.27 1.27)) (justify left bottom))
  )
  (text "Populated" (at 272.796 265.176 0)
    (effects (font (size 1.27 1.27)) (justify left bottom))
  )
  (text "R32" (at 264.16 257.556 0)
    (effects (font (size 1.27 1.27)) (justify left bottom))
  )
  (text "DNP\n" (at 287.02 270.256 0)
    (effects (font (size 1.27 1.27)) (justify left bottom))
  )
  (text "PSU connector" (at 160.02 125.73 0)
    (effects (font (size 2.9972 2.9972)) (justify left bottom))
  )
  (text "Populated" (at 272.796 272.796 0)
    (effects (font (size 1.27 1.27)) (justify left bottom))
  )
  (text "R39" (at 264.16 270.256 0)
    (effects (font (size 1.27 1.27)) (justify left bottom))
  )
  (text "Populated" (at 272.796 277.876 0)
    (effects (font (size 1.27 1.27)) (justify left bottom))
  )
  (text "Populated" (at 272.796 280.416 0)
    (effects (font (size 1.27 1.27)) (justify left bottom))
  )
  (text "R13\n" (at 264.16 252.476 0)
    (effects (font (size 1.27 1.27)) (justify left bottom))
  )
  (text "R38" (at 264.16 267.716 0)
    (effects (font (size 1.27 1.27)) (justify left bottom))
  )
  (text "DNP\n" (at 287.02 260.096 0)
    (effects (font (size 1.27 1.27)) (justify left bottom))
  )
  (text "R37" (at 264.16 265.176 0)
    (effects (font (size 1.27 1.27)) (justify left bottom))
  )
  (text "R36" (at 264.16 262.636 0)
    (effects (font (size 1.27 1.27)) (justify left bottom))
  )
  (text "Note: Verify the PSU pinout\nbefore connecting the board"
    (at 166.37 207.01 0)
    (effects (font (size 2.9972 2.9972)) (justify left bottom))
  )
  (text "Populated" (at 284.48 257.556 0)
    (effects (font (size 1.27 1.27)) (justify left bottom))
  )
  (text "Power Indicators" (at 147.32 227.33 0)
    (effects (font (size 2.9972 2.9972)) (justify left bottom))
  )
  (text "Design variants" (at 275.59 246.38 0)
    (effects (font (size 1.27 1.27) (thickness 0.254) bold) (justify left bottom))
  )
  (text "DNP\n" (at 287.02 262.636 0)
    (effects (font (size 1.27 1.27)) (justify left bottom))
  )
  (text "Populated" (at 272.796 255.016 0)
    (effects (font (size 1.27 1.27)) (justify left bottom))
  )
  (text "J1" (at 264.795 277.876 0)
    (effects (font (size 1.27 1.27)) (justify left bottom))
  )
  (text "ALWAYS_ON 12V0\n" (at 209.55 160.02 0)
    (effects (font (size 1.27 1.27)) (justify left bottom))
  )
  (text "D1600E PSU Breakout Board" (at 15.875 23.495 0)
    (effects (font (size 3 3) (thickness 0.6) bold) (justify left bottom))
  )
  (text "BOARD TO BOARD CONNECTION" (at 25.4 40.64 0)
    (effects (font (size 2.9972 2.9972)) (justify left bottom))
  )
  (text "Populated" (at 272.796 270.256 0)
    (effects (font (size 1.27 1.27)) (justify left bottom))
  )
  (text "DNP\n" (at 275.59 252.476 0)
    (effects (font (size 1.27 1.27)) (justify left bottom))
  )
  (text "DNP\n" (at 287.02 265.176 0)
    (effects (font (size 1.27 1.27)) (justify left bottom))
  )
  (text "Output Connectors" (at 25.4 119.38 0)
    (effects (font (size 2.9972 2.9972)) (justify left bottom))
  )
  (text "Master" (at 274.32 249.555 0)
    (effects (font (size 1.27 1.27) (thickness 0.254) bold) (justify left bottom))
  )
  (text "Populated" (at 284.48 252.476 0)
    (effects (font (size 1.27 1.27)) (justify left bottom))
  )
  (text "DNP\n" (at 287.02 272.796 0)
    (effects (font (size 1.27 1.27)) (justify left bottom))
  )
  (text "R14" (at 264.16 255.016 0)
    (effects (font (size 1.27 1.27)) (justify left bottom))
  )
  (text "Populated" (at 272.796 267.716 0)
    (effects (font (size 1.27 1.27)) (justify left bottom))
  )
  (text "Component" (at 260.35 249.555 0)
    (effects (font (size 1.27 1.27) (thickness 0.254) bold) (justify left bottom))
  )
  (text "U5" (at 264.668 280.416 0)
    (effects (font (size 1.27 1.27)) (justify left bottom))
  )
  (text "DNP\n" (at 287.02 277.876 0)
    (effects (font (size 1.27 1.27)) (justify left bottom))
  )
  (text "R42" (at 264.16 272.796 0)
    (effects (font (size 1.27 1.27)) (justify left bottom))
  )
  (text "Slave" (at 286.385 249.555 0)
    (effects (font (size 1.27 1.27) (thickness 0.254) bold) (justify left bottom))
  )
  (text "R33" (at 264.16 260.096 0)
    (effects (font (size 1.27 1.27)) (justify left bottom))
  )
  (text "Populated" (at 272.796 275.336 0)
    (effects (font (size 1.27 1.27)) (justify left bottom))
  )
  (text "DNP\n" (at 287.02 255.016 0)
    (effects (font (size 1.27 1.27)) (justify left bottom))
  )
  (text "DNP\n" (at 275.59 257.556 0)
    (effects (font (size 1.27 1.27)) (justify left bottom))
  )
  (text "DNP\n" (at 287.02 267.716 0)
    (effects (font (size 1.27 1.27)) (justify left bottom))
  )

  (global_label "VCC5V0" (shape input) (at 44.45 201.93 180) (fields_autoplaced)
    (effects (font (size 1.27 1.27)) (justify right))
    (property "Intersheetrefs" "${INTERSHEET_REFS}" (at -189.23 144.78 0)
      (effects (font (size 1.27 1.27)) hide)
    )
  )
  (global_label "SCL" (shape input) (at 90.17 74.93 180) (fields_autoplaced)
    (effects (font (size 1.27 1.27)) (justify right))
    (property "Intersheetrefs" "${INTERSHEET_REFS}" (at 9.525 18.415 0)
      (effects (font (size 1.27 1.27)) hide)
    )
  )
  (global_label "LOAD_2" (shape input) (at 165.1 242.57 90) (fields_autoplaced)
    (effects (font (size 1.27 1.27)) (justify left))
    (property "Intersheetrefs" "${INTERSHEET_REFS}" (at 165.0206 233.3515 90)
      (effects (font (size 1.27 1.27)) (justify left) hide)
    )
  )
  (global_label "VCC3V3" (shape input) (at 222.25 55.88 90) (fields_autoplaced)
    (effects (font (size 1.27 1.27)) (justify left))
    (property "Intersheetrefs" "${INTERSHEET_REFS}" (at 64.77 31.115 0)
      (effects (font (size 1.27 1.27)) hide)
    )
  )
  (global_label "LOAD_1" (shape input) (at 152.4 242.57 90) (fields_autoplaced)
    (effects (font (size 1.27 1.27)) (justify left))
    (property "Intersheetrefs" "${INTERSHEET_REFS}" (at 250.825 206.375 0)
      (effects (font (size 1.27 1.27)) hide)
    )
  )
  (global_label "VCC5V0" (shape input) (at 227.33 242.57 90) (fields_autoplaced)
    (effects (font (size 1.27 1.27)) (justify left))
    (property "Intersheetrefs" "${INTERSHEET_REFS}" (at 284.48 8.89 0)
      (effects (font (size 1.27 1.27)) hide)
    )
  )
  (global_label "PSU_ON" (shape input) (at 182.88 77.47 180) (fields_autoplaced)
    (effects (font (size 1.27 1.27)) (justify right))
    (property "Intersheetrefs" "${INTERSHEET_REFS}" (at 55.88 33.02 0)
      (effects (font (size 1.27 1.27)) hide)
    )
  )
  (global_label "VCC5V0" (shape input) (at 91.44 201.93 180) (fields_autoplaced)
    (effects (font (size 1.27 1.27)) (justify right))
    (property "Intersheetrefs" "${INTERSHEET_REFS}" (at -142.24 144.78 0)
      (effects (font (size 1.27 1.27)) hide)
    )
  )
  (global_label "VCC12V0" (shape output) (at 173.99 137.16 180) (fields_autoplaced)
    (effects (font (size 1.27 1.27)) (justify right))
    (property "Intersheetrefs" "${INTERSHEET_REFS}" (at 46.355 41.91 0)
      (effects (font (size 1.27 1.27)) hide)
    )
  )
  (global_label "VCC5V0" (shape input) (at 44.45 217.17 180) (fields_autoplaced)
    (effects (font (size 1.27 1.27)) (justify right))
    (property "Intersheetrefs" "${INTERSHEET_REFS}" (at -189.23 160.02 0)
      (effects (font (size 1.27 1.27)) hide)
    )
  )
  (global_label "PSU_ON" (shape input) (at 226.06 187.96 0) (fields_autoplaced)
    (effects (font (size 1.27 1.27)) (justify left))
    (property "Intersheetrefs" "${INTERSHEET_REFS}" (at 50.8 53.34 0)
      (effects (font (size 1.27 1.27)) hide)
    )
  )
  (global_label "VCC12V0" (shape input) (at 44.45 209.55 180) (fields_autoplaced)
    (effects (font (size 1.27 1.27)) (justify right))
    (property "Intersheetrefs" "${INTERSHEET_REFS}" (at -189.23 156.21 0)
      (effects (font (size 1.27 1.27)) hide)
    )
  )
  (global_label "VCC5V0" (shape input) (at 91.44 229.87 180) (fields_autoplaced)
    (effects (font (size 1.27 1.27)) (justify right))
    (property "Intersheetrefs" "${INTERSHEET_REFS}" (at -142.24 172.72 0)
      (effects (font (size 1.27 1.27)) hide)
    )
  )
  (global_label "SDA_CON" (shape input) (at 102.87 99.06 180) (fields_autoplaced)
    (effects (font (size 1.27 1.27)) (justify right))
    (property "Intersheetrefs" "${INTERSHEET_REFS}" (at 92.0791 98.9806 0)
      (effects (font (size 1.27 1.27)) (justify right) hide)
    )
  )
  (global_label "LOAD_4" (shape input) (at 77.47 154.94 180) (fields_autoplaced)
    (effects (font (size 1.27 1.27)) (justify right))
    (property "Intersheetrefs" "${INTERSHEET_REFS}" (at -0.635 32.385 0)
      (effects (font (size 1.27 1.27)) hide)
    )
  )
  (global_label "VCC12V0" (shape input) (at 91.44 209.55 180) (fields_autoplaced)
    (effects (font (size 1.27 1.27)) (justify right))
    (property "Intersheetrefs" "${INTERSHEET_REFS}" (at -142.24 156.21 0)
      (effects (font (size 1.27 1.27)) hide)
    )
  )
  (global_label "LOAD_5" (shape input) (at 77.47 177.8 180) (fields_autoplaced)
    (effects (font (size 1.27 1.27)) (justify right))
    (property "Intersheetrefs" "${INTERSHEET_REFS}" (at 22.225 26.035 0)
      (effects (font (size 1.27 1.27)) hide)
    )
  )
  (global_label "LOAD_3" (shape input) (at 41.91 153.67 180) (fields_autoplaced)
    (effects (font (size 1.27 1.27)) (justify right))
    (property "Intersheetrefs" "${INTERSHEET_REFS}" (at 5.715 31.115 0)
      (effects (font (size 1.27 1.27)) hide)
    )
  )
  (global_label "SDA" (shape input) (at 90.17 72.39 180) (fields_autoplaced)
    (effects (font (size 1.27 1.27)) (justify right))
    (property "Intersheetrefs" "${INTERSHEET_REFS}" (at 9.525 18.415 0)
      (effects (font (size 1.27 1.27)) hide)
    )
  )
  (global_label "VCC12V0" (shape input) (at 91.44 224.79 180) (fields_autoplaced)
    (effects (font (size 1.27 1.27)) (justify right))
    (property "Intersheetrefs" "${INTERSHEET_REFS}" (at -142.24 171.45 0)
      (effects (font (size 1.27 1.27)) hide)
    )
  )
  (global_label "LOAD_4" (shape input) (at 190.5 242.57 90) (fields_autoplaced)
    (effects (font (size 1.27 1.27)) (justify left))
    (property "Intersheetrefs" "${INTERSHEET_REFS}" (at 190.4206 233.3515 90)
      (effects (font (size 1.27 1.27)) (justify left) hide)
    )
  )
  (global_label "LED_DATA" (shape input) (at 88.9 64.77 180) (fields_autoplaced)
    (effects (font (size 1.27 1.27)) (justify right))
    (property "Intersheetrefs" "${INTERSHEET_REFS}" (at 77.7463 64.8494 0)
      (effects (font (size 1.27 1.27)) (justify right) hide)
    )
  )
  (global_label "VCC12V0" (shape input) (at 44.45 224.79 180) (fields_autoplaced)
    (effects (font (size 1.27 1.27)) (justify right))
    (property "Intersheetrefs" "${INTERSHEET_REFS}" (at -189.23 171.45 0)
      (effects (font (size 1.27 1.27)) hide)
    )
  )
  (global_label "VCC12V0" (shape input) (at 91.44 237.49 180) (fields_autoplaced)
    (effects (font (size 1.27 1.27)) (justify right))
    (property "Intersheetrefs" "${INTERSHEET_REFS}" (at -142.24 184.15 0)
      (effects (font (size 1.27 1.27)) hide)
    )
  )
  (global_label "LOAD_2" (shape input) (at 77.47 132.08 180) (fields_autoplaced)
    (effects (font (size 1.27 1.27)) (justify right))
    (property "Intersheetrefs" "${INTERSHEET_REFS}" (at 0.635 33.655 0)
      (effects (font (size 1.27 1.27)) hide)
    )
  )
  (global_label "SDA_CON" (shape input) (at 88.9 67.31 180) (fields_autoplaced)
    (effects (font (size 1.27 1.27)) (justify right))
    (property "Intersheetrefs" "${INTERSHEET_REFS}" (at 78.1091 67.2306 0)
      (effects (font (size 1.27 1.27)) (justify right) hide)
    )
  )
  (global_label "LOAD_3" (shape input) (at 177.8 242.57 90) (fields_autoplaced)
    (effects (font (size 1.27 1.27)) (justify left))
    (property "Intersheetrefs" "${INTERSHEET_REFS}" (at 177.7206 233.3515 90)
      (effects (font (size 1.27 1.27)) (justify left) hide)
    )
  )
  (global_label "VCC5V0" (shape input) (at 91.44 217.17 180) (fields_autoplaced)
    (effects (font (size 1.27 1.27)) (justify right))
    (property "Intersheetrefs" "${INTERSHEET_REFS}" (at -142.24 160.02 0)
      (effects (font (size 1.27 1.27)) hide)
    )
  )
  (global_label "VCC3V3" (shape input) (at 215.9 242.57 90) (fields_autoplaced)
    (effects (font (size 1.27 1.27)) (justify left))
    (property "Intersheetrefs" "${INTERSHEET_REFS}" (at 265.43 8.89 0)
      (effects (font (size 1.27 1.27)) hide)
    )
  )
  (global_label "SCL" (shape bidirectional) (at 102.87 96.52 180) (fields_autoplaced)
    (effects (font (size 1.27 1.27)) (justify right))
    (property "Intersheetrefs" "${INTERSHEET_REFS}" (at 207.01 332.105 0)
      (effects (font (size 1.27 1.27)) hide)
    )
  )
  (global_label "SCL" (shape input) (at 39.37 74.93 180) (fields_autoplaced)
    (effects (font (size 1.27 1.27)) (justify right))
    (property "Intersheetrefs" "${INTERSHEET_REFS}" (at 3.175 18.415 0)
      (effects (font (size 1.27 1.27)) hide)
    )
  )
  (global_label "SCL" (shape bidirectional) (at 36.83 96.52 180) (fields_autoplaced)
    (effects (font (size 1.27 1.27)) (justify right))
    (property "Intersheetrefs" "${INTERSHEET_REFS}" (at 140.97 332.105 0)
      (effects (font (size 1.27 1.27)) hide)
    )
  )
  (global_label "VCC3V3" (shape input) (at 109.22 54.61 90) (fields_autoplaced)
    (effects (font (size 1.27 1.27)) (justify left))
    (property "Intersheetrefs" "${INTERSHEET_REFS}" (at 28.575 18.415 0)
      (effects (font (size 1.27 1.27)) hide)
    )
  )
  (global_label "VCC3V3" (shape input) (at 39.37 54.61 90) (fields_autoplaced)
    (effects (font (size 1.27 1.27)) (justify left))
    (property "Intersheetrefs" "${INTERSHEET_REFS}" (at 3.175 18.415 0)
      (effects (font (size 1.27 1.27)) hide)
    )
  )
  (global_label "SDA" (shape input) (at 39.37 72.39 180) (fields_autoplaced)
    (effects (font (size 1.27 1.27)) (justify right))
    (property "Intersheetrefs" "${INTERSHEET_REFS}" (at 3.175 18.415 0)
      (effects (font (size 1.27 1.27)) hide)
    )
  )
  (global_label "LOAD_1" (shape input) (at 41.91 130.81 180) (fields_autoplaced)
    (effects (font (size 1.27 1.27)) (justify right))
    (property "Intersheetrefs" "${INTERSHEET_REFS}" (at 5.715 32.385 0)
      (effects (font (size 1.27 1.27)) hide)
    )
  )
  (global_label "SDA" (shape bidirectional) (at 36.83 99.06 180) (fields_autoplaced)
    (effects (font (size 1.27 1.27)) (justify right))
    (property "Intersheetrefs" "${INTERSHEET_REFS}" (at 140.97 332.105 0)
      (effects (font (size 1.27 1.27)) hide)
    )
  )
  (global_label "VCC12V0" (shape output) (at 222.25 137.16 0) (fields_autoplaced)
    (effects (font (size 1.27 1.27)) (justify left))
    (property "Intersheetrefs" "${INTERSHEET_REFS}" (at 51.435 41.91 0)
      (effects (font (size 1.27 1.27)) hide)
    )
  )
  (global_label "LOAD_5" (shape input) (at 203.2 242.57 90) (fields_autoplaced)
    (effects (font (size 1.27 1.27)) (justify left))
    (property "Intersheetrefs" "${INTERSHEET_REFS}" (at 354.965 187.325 0)
      (effects (font (size 1.27 1.27)) hide)
    )
  )
  (global_label "VCC12V0" (shape input) (at 238.76 242.57 90) (fields_autoplaced)
    (effects (font (size 1.27 1.27)) (justify left))
    (property "Intersheetrefs" "${INTERSHEET_REFS}" (at 292.1 8.89 0)
      (effects (font (size 1.27 1.27)) hide)
    )
  )

  (symbol (lib_name "JST_SH_1x4_BM04B-SRSS-TB-LF-SN_1") (lib_id "antmicroWire2BoardConnectors:JST_SH_1x4_BM04B-SRSS-TB-LF-SN") (at 43.18 69.85 0) (unit 1)
    (in_bom no) (on_board yes) (dnp yes) (fields_autoplaced)
    (property "Reference" "J2" (at 49.53 72.39 0)
      (effects (font (size 1.27 1.27)) (justify left))
    )
    (property "Value" "JST_SH_1x4_BM04B-SRSS-TB-LF-SN" (at 63.5 77.47 0)
      (effects (font (size 1.27 1.27) (thickness 0.15)) (justify left bottom) hide)
    )
    (property "Footprint" "antmicro-footprints:Conn_JST_SH_1x4_BM04B-SRSS-TB-LF-SN" (at 63.5 80.01 0)
      (effects (font (size 1.27 1.27) (thickness 0.15)) (justify left bottom) hide)
    )
    (property "Datasheet" "https://www.jst-mfg.com/product/pdf/eng/eSH.pdf" (at 63.5 82.55 0)
      (effects (font (size 1.27 1.27) (thickness 0.15)) (justify left bottom) hide)
    )
    (property "MPN" "BM04B-SRSS-TB(LF)(SN) " (at 49.53 74.93 0)
      (effects (font (size 1.27 1.27) (thickness 0.15)) (justify left))
    )
    (property "Manufacturer" "JST Automotive Connectors" (at 63.5 87.63 0)
      (effects (font (size 1.27 1.27) (thickness 0.15)) (justify left bottom) hide)
    )
    (property "DNP" "DNP" (at 49.53 77.47 0)
      (effects (font (size 1.27 1.27)) (justify left))
    )
    (property "Author" "Antmicro" (at 63.5 90.17 0)
      (effects (font (size 1.27 1.27) (thickness 0.15)) (justify left bottom) hide)
    )
    (property "License" "Apache-2.0" (at 63.5 92.71 0)
      (effects (font (size 1.27 1.27) (thickness 0.15)) (justify left bottom) hide)
    )
    (pin "1")
    (pin "2")
    (pin "3")
    (pin "4")
    (pin "MP")
    (instances
      (project "d1600e-psu-breakout-board"
        (path ""
          (reference "J2") (unit 1)
        )
      )
    )
  )

  (symbol (lib_id "antmicroWire2BoardConnectors:JST_SH_1x4_BM04B-SRSS-TB-LF-SN") (at 113.03 69.85 0) (unit 1)
    (in_bom yes) (on_board yes) (dnp no) (fields_autoplaced)
    (property "Reference" "J3" (at 119.38 73.66 0)
      (effects (font (size 1.27 1.27)) (justify left))
    )
    (property "Value" "JST_SH_1x4_BM04B-SRSS-TB-LF-SN" (at 133.35 77.47 0)
      (effects (font (size 1.27 1.27) (thickness 0.15)) (justify left bottom) hide)
    )
    (property "Footprint" "antmicro-footprints:Conn_JST_SH_1x4_BM04B-SRSS-TB-LF-SN" (at 133.35 80.01 0)
      (effects (font (size 1.27 1.27) (thickness 0.15)) (justify left bottom) hide)
    )
    (property "Datasheet" "https://www.jst-mfg.com/product/pdf/eng/eSH.pdf" (at 133.35 82.55 0)
      (effects (font (size 1.27 1.27) (thickness 0.15)) (justify left bottom) hide)
    )
    (property "MPN" "BM04B-SRSS-TB(LF)(SN) " (at 119.38 76.2 0)
      (effects (font (size 1.27 1.27) (thickness 0.15)) (justify left))
    )
    (property "Manufacturer" "JST Automotive Connectors" (at 133.35 87.63 0)
      (effects (font (size 1.27 1.27) (thickness 0.15)) (justify left bottom) hide)
    )
    (property "Author" "Antmicro" (at 133.35 90.17 0)
      (effects (font (size 1.27 1.27) (thickness 0.15)) (justify left bottom) hide)
    )
    (property "License" "Apache-2.0" (at 133.35 92.71 0)
      (effects (font (size 1.27 1.27) (thickness 0.15)) (justify left bottom) hide)
    )
    (pin "1")
    (pin "2")
    (pin "3")
    (pin "4")
    (pin "MP")
    (instances
      (project "d1600e-psu-breakout-board"
        (path ""
          (reference "J3") (unit 1)
        )
      )
    )
  )

  (symbol (lib_id "antmicropower:GND") (at 39.37 80.01 0) (unit 1)
    (in_bom yes) (on_board yes) (dnp no)
    (property "Reference" "#PWR023" (at 39.37 86.36 0)
      (effects (font (size 1.27 1.27)) hide)
    )
    (property "Value" "GND" (at 39.37 83.82 0)
      (effects (font (size 1.27 1.27) (thickness 0.15)))
    )
    (property "Footprint" "" (at 48.26 87.63 0)
      (effects (font (size 1.27 1.27) (thickness 0.15)) (justify left bottom) hide)
    )
    (property "Datasheet" "" (at 48.26 92.71 0)
      (effects (font (size 1.27 1.27) (thickness 0.15)) (justify left bottom) hide)
    )
    (property "Author" "Antmicro" (at 48.26 87.63 0)
      (effects (font (size 1.27 1.27) (thickness 0.15)) (justify left bottom) hide)
    )
    (property "License" "Apache-2.0" (at 48.26 90.17 0)
      (effects (font (size 1.27 1.27) (thickness 0.15)) (justify left bottom) hide)
    )
    (pin "1")
    (instances
      (project "d1600e-psu-breakout-board"
        (path ""
          (reference "#PWR023") (unit 1)
        )
      )
    )
  )

  (symbol (lib_id "antmicropower:GND") (at 165.1 158.75 0) (unit 1)
    (in_bom yes) (on_board yes) (dnp no)
    (property "Reference" "#PWR033" (at 165.1 165.1 0)
      (effects (font (size 1.27 1.27)) hide)
    )
    (property "Value" "GND" (at 165.1 162.56 0)
      (effects (font (size 1.27 1.27) (thickness 0.15)))
    )
    (property "Footprint" "" (at 173.99 166.37 0)
      (effects (font (size 1.27 1.27) (thickness 0.15)) (justify left bottom) hide)
    )
    (property "Datasheet" "" (at 173.99 171.45 0)
      (effects (font (size 1.27 1.27) (thickness 0.15)) (justify left bottom) hide)
    )
    (property "Author" "Antmicro" (at 173.99 166.37 0)
      (effects (font (size 1.27 1.27) (thickness 0.15)) (justify left bottom) hide)
    )
    (property "License" "Apache-2.0" (at 173.99 168.91 0)
      (effects (font (size 1.27 1.27) (thickness 0.15)) (justify left bottom) hide)
    )
    (pin "1")
    (instances
      (project "d1600e-psu-breakout-board"
        (path ""
          (reference "#PWR033") (unit 1)
        )
      )
    )
  )

  (symbol (lib_name "R_0R_0402_1") (lib_id "antmicroResistors0402:R_0R_0402") (at 39.37 59.69 270) (unit 1)
    (in_bom no) (on_board yes) (dnp yes)
    (property "Reference" "R9" (at 40.64 59.69 90)
      (effects (font (size 1.27 1.27)) (justify left))
    )
    (property "Value" "R_0R_0402" (at 26.67 80.01 0)
      (effects (font (size 1.27 1.27) (thickness 0.15)) (justify left bottom) hide)
    )
    (property "Footprint" "antmicro-footprints:R_0402_1005Metric" (at 24.13 80.01 0)
      (effects (font (size 1.27 1.27) (thickness 0.15)) (justify left bottom) hide)
    )
    (property "Datasheet" "https://industrial.panasonic.com/cdbs/www-data/pdf/RDA0000/AOA0000C301.pdf" (at 21.59 80.01 0)
      (effects (font (size 1.27 1.27) (thickness 0.15)) (justify left bottom) hide)
    )
    (property "Manufacturer" "Panasonic" (at 16.51 80.01 0)
      (effects (font (size 1.27 1.27) (thickness 0.15)) (justify left bottom) hide)
    )
    (property "MPN" "ERJ2GE0R00X" (at 19.05 80.01 0)
      (effects (font (size 1.27 1.27) (thickness 0.15)) (justify left bottom) hide)
    )
    (property "Val" "0R" (at 40.64 62.23 90)
      (effects (font (size 1.27 1.27) (thickness 0.15)) (justify left))
    )
    (property "DNP" "DNP" (at 40.64 64.77 90)
      (effects (font (size 1.27 1.27)) (justify left))
    )
    (property "License" "Apache-2.0" (at 13.97 80.01 0)
      (effects (font (size 1.27 1.27) (thickness 0.15)) (justify left bottom) hide)
    )
    (property "Author" "Antmicro" (at 11.43 80.01 0)
      (effects (font (size 1.27 1.27) (thickness 0.15)) (justify left bottom) hide)
    )
    (property "Tolerance" "~" (at 29.21 80.01 0)
      (effects (font (size 1.27 1.27)) (justify left bottom) hide)
    )
    (property "Current" "1A" (at 8.89 80.01 0)
      (effects (font (size 1.27 1.27) (thickness 0.15)) (justify left bottom) hide)
    )
    (pin "1")
    (pin "2")
    (instances
      (project "d1600e-psu-breakout-board"
        (path ""
          (reference "R9") (unit 1)
        )
      )
    )
  )

  (symbol (lib_name "R_0R_0402_4") (lib_id "antmicroResistors0402:R_0R_0402") (at 109.22 59.69 270) (unit 1)
    (in_bom no) (on_board yes) (dnp yes) (fields_autoplaced)
    (property "Reference" "R10" (at 111.76 59.69 90)
      (effects (font (size 1.27 1.27)) (justify left))
    )
    (property "Value" "R_0R_0402" (at 96.52 80.01 0)
      (effects (font (size 1.27 1.27) (thickness 0.15)) (justify left bottom) hide)
    )
    (property "Footprint" "antmicro-footprints:R_0402_1005Metric" (at 93.98 80.01 0)
      (effects (font (size 1.27 1.27) (thickness 0.15)) (justify left bottom) hide)
    )
    (property "Datasheet" "https://industrial.panasonic.com/cdbs/www-data/pdf/RDA0000/AOA0000C301.pdf" (at 91.44 80.01 0)
      (effects (font (size 1.27 1.27) (thickness 0.15)) (justify left bottom) hide)
    )
    (property "Manufacturer" "Panasonic" (at 86.36 80.01 0)
      (effects (font (size 1.27 1.27) (thickness 0.15)) (justify left bottom) hide)
    )
    (property "MPN" "ERJ2GE0R00X" (at 88.9 80.01 0)
      (effects (font (size 1.27 1.27) (thickness 0.15)) (justify left bottom) hide)
    )
    (property "Val" "0R" (at 111.76 62.23 90)
      (effects (font (size 1.27 1.27) (thickness 0.15)) (justify left))
    )
    (property "DNP" "DNP" (at 111.76 64.77 90)
      (effects (font (size 1.27 1.27)) (justify left))
    )
    (property "License" "Apache-2.0" (at 83.82 80.01 0)
      (effects (font (size 1.27 1.27) (thickness 0.15)) (justify left bottom) hide)
    )
    (property "Author" "Antmicro" (at 81.28 80.01 0)
      (effects (font (size 1.27 1.27) (thickness 0.15)) (justify left bottom) hide)
    )
    (property "Tolerance" "~" (at 99.06 80.01 0)
      (effects (font (size 1.27 1.27)) (justify left bottom) hide)
    )
    (property "Current" "1A" (at 78.74 80.01 0)
      (effects (font (size 1.27 1.27) (thickness 0.15)) (justify left bottom) hide)
    )
    (pin "1")
    (pin "2")
    (instances
      (project "d1600e-psu-breakout-board"
        (path ""
          (reference "R10") (unit 1)
        )
      )
    )
  )

  (symbol (lib_id "antmicropower:GND") (at 63.5 140.97 0) (unit 1)
    (in_bom yes) (on_board yes) (dnp no)
    (property "Reference" "#PWR027" (at 63.5 147.32 0)
      (effects (font (size 1.27 1.27)) hide)
    )
    (property "Value" "GND" (at 63.5 144.78 0)
      (effects (font (size 1.27 1.27) (thickness 0.15)))
    )
    (property "Footprint" "" (at 72.39 148.59 0)
      (effects (font (size 1.27 1.27) (thickness 0.15)) (justify left bottom) hide)
    )
    (property "Datasheet" "" (at 72.39 153.67 0)
      (effects (font (size 1.27 1.27) (thickness 0.15)) (justify left bottom) hide)
    )
    (property "Author" "Antmicro" (at 72.39 148.59 0)
      (effects (font (size 1.27 1.27) (thickness 0.15)) (justify left bottom) hide)
    )
    (property "License" "Apache-2.0" (at 72.39 151.13 0)
      (effects (font (size 1.27 1.27) (thickness 0.15)) (justify left bottom) hide)
    )
    (pin "1")
    (instances
      (project "d1600e-psu-breakout-board"
        (path ""
          (reference "#PWR027") (unit 1)
        )
      )
    )
  )

  (symbol (lib_id "antmicropower:GND") (at 63.5 163.83 0) (unit 1)
    (in_bom yes) (on_board yes) (dnp no)
    (property "Reference" "#PWR030" (at 63.5 170.18 0)
      (effects (font (size 1.27 1.27)) hide)
    )
    (property "Value" "GND" (at 63.5 167.64 0)
      (effects (font (size 1.27 1.27) (thickness 0.15)))
    )
    (property "Footprint" "" (at 72.39 171.45 0)
      (effects (font (size 1.27 1.27) (thickness 0.15)) (justify left bottom) hide)
    )
    (property "Datasheet" "" (at 72.39 176.53 0)
      (effects (font (size 1.27 1.27) (thickness 0.15)) (justify left bottom) hide)
    )
    (property "Author" "Antmicro" (at 72.39 171.45 0)
      (effects (font (size 1.27 1.27) (thickness 0.15)) (justify left bottom) hide)
    )
    (property "License" "Apache-2.0" (at 72.39 173.99 0)
      (effects (font (size 1.27 1.27) (thickness 0.15)) (justify left bottom) hide)
    )
    (pin "1")
    (instances
      (project "d1600e-psu-breakout-board"
        (path ""
          (reference "#PWR030") (unit 1)
        )
      )
    )
  )

  (symbol (lib_id "antmicropower:GND") (at 99.06 165.1 0) (unit 1)
    (in_bom yes) (on_board yes) (dnp no)
    (property "Reference" "#PWR035" (at 99.06 171.45 0)
      (effects (font (size 1.27 1.27)) hide)
    )
    (property "Value" "GND" (at 99.06 168.91 0)
      (effects (font (size 1.27 1.27) (thickness 0.15)))
    )
    (property "Footprint" "" (at 107.95 172.72 0)
      (effects (font (size 1.27 1.27) (thickness 0.15)) (justify left bottom) hide)
    )
    (property "Datasheet" "" (at 107.95 177.8 0)
      (effects (font (size 1.27 1.27) (thickness 0.15)) (justify left bottom) hide)
    )
    (property "Author" "Antmicro" (at 107.95 172.72 0)
      (effects (font (size 1.27 1.27) (thickness 0.15)) (justify left bottom) hide)
    )
    (property "License" "Apache-2.0" (at 107.95 175.26 0)
      (effects (font (size 1.27 1.27) (thickness 0.15)) (justify left bottom) hide)
    )
    (pin "1")
    (instances
      (project "d1600e-psu-breakout-board"
        (path ""
          (reference "#PWR035") (unit 1)
        )
      )
    )
  )

  (symbol (lib_id "antmicropower:GND") (at 99.06 187.96 0) (unit 1)
    (in_bom yes) (on_board yes) (dnp no)
    (property "Reference" "#PWR031" (at 99.06 194.31 0)
      (effects (font (size 1.27 1.27)) hide)
    )
    (property "Value" "GND" (at 99.06 191.77 0)
      (effects (font (size 1.27 1.27) (thickness 0.15)))
    )
    (property "Footprint" "" (at 107.95 195.58 0)
      (effects (font (size 1.27 1.27) (thickness 0.15)) (justify left bottom) hide)
    )
    (property "Datasheet" "" (at 107.95 200.66 0)
      (effects (font (size 1.27 1.27) (thickness 0.15)) (justify left bottom) hide)
    )
    (property "Author" "Antmicro" (at 107.95 195.58 0)
      (effects (font (size 1.27 1.27) (thickness 0.15)) (justify left bottom) hide)
    )
    (property "License" "Apache-2.0" (at 107.95 198.12 0)
      (effects (font (size 1.27 1.27) (thickness 0.15)) (justify left bottom) hide)
    )
    (pin "1")
    (instances
      (project "d1600e-psu-breakout-board"
        (path ""
          (reference "#PWR031") (unit 1)
        )
      )
    )
  )

  (symbol (lib_id "antmicropower:GND") (at 99.06 142.24 0) (unit 1)
    (in_bom yes) (on_board yes) (dnp no)
    (property "Reference" "#PWR034" (at 99.06 148.59 0)
      (effects (font (size 1.27 1.27)) hide)
    )
    (property "Value" "GND" (at 99.06 146.05 0)
      (effects (font (size 1.27 1.27) (thickness 0.15)))
    )
    (property "Footprint" "" (at 107.95 149.86 0)
      (effects (font (size 1.27 1.27) (thickness 0.15)) (justify left bottom) hide)
    )
    (property "Datasheet" "" (at 107.95 154.94 0)
      (effects (font (size 1.27 1.27) (thickness 0.15)) (justify left bottom) hide)
    )
    (property "Author" "Antmicro" (at 107.95 149.86 0)
      (effects (font (size 1.27 1.27) (thickness 0.15)) (justify left bottom) hide)
    )
    (property "License" "Apache-2.0" (at 107.95 152.4 0)
      (effects (font (size 1.27 1.27) (thickness 0.15)) (justify left bottom) hide)
    )
    (pin "1")
    (instances
      (project "d1600e-psu-breakout-board"
        (path ""
          (reference "#PWR034") (unit 1)
        )
      )
    )
  )

  (symbol (lib_id "antmicroEdgeConnectors:Socket_Amphenol_HPCE_2x17_10107844-002LF") (at 180.34 137.16 0) (unit 1)
    (in_bom yes) (on_board yes) (dnp no) (fields_autoplaced)
    (property "Reference" "J10" (at 198.12 129.54 0)
      (effects (font (size 1.27 1.27)))
    )
    (property "Value" "Socket_Amphenol_HPCE_2x17_10107844-002LF" (at 231.14 144.78 0)
      (effects (font (size 1.27 1.27) (thickness 0.15)) (justify left bottom) hide)
    )
    (property "Footprint" "antmicro-footprints:Socket_Amphenol_HPCE_2x17_10107844-002LF" (at 231.14 147.32 0)
      (effects (font (size 1.27 1.27) (thickness 0.15)) (justify left bottom) hide)
    )
    (property "Datasheet" "https://www.farnell.com/cad/2569863.pdf" (at 231.14 149.86 0)
      (effects (font (size 1.27 1.27) (thickness 0.15)) (justify left bottom) hide)
    )
    (property "MPN" "10107844-002LF" (at 198.12 132.08 0)
      (effects (font (size 1.27 1.27) (thickness 0.15)))
    )
    (property "Manufacturer" "Amphenol" (at 231.14 152.4 0)
      (effects (font (size 1.27 1.27) (thickness 0.15)) (justify left bottom) hide)
    )
    (property "Author" "Antmicro" (at 231.14 154.94 0)
      (effects (font (size 1.27 1.27) (thickness 0.15)) (justify left bottom) hide)
    )
    (property "License" "Apache-2.0" (at 231.14 157.48 0)
      (effects (font (size 1.27 1.27) (thickness 0.15)) (justify left bottom) hide)
    )
    (pin "P1/2")
    (pin "P11/12")
    (pin "P13/14")
    (pin "P15/16")
    (pin "P17/18")
    (pin "P19/20")
    (pin "P21/22")
    (pin "P23/24")
    (pin "P25/26")
    (pin "P27/28")
    (pin "P29/30")
    (pin "P3/4")
    (pin "P31/32")
    (pin "P33/34")
    (pin "P35/36")
    (pin "P5/6")
    (pin "P7/8")
    (pin "P9/10")
    (pin "S1")
    (pin "S10")
    (pin "S11")
    (pin "S12")
    (pin "S13")
    (pin "S14")
    (pin "S15")
    (pin "S16")
    (pin "S17")
    (pin "S18")
    (pin "S19")
    (pin "S2")
    (pin "S20")
    (pin "S21")
    (pin "S22")
    (pin "S23")
    (pin "S24")
    (pin "S3")
    (pin "S4")
    (pin "S5")
    (pin "S6")
    (pin "S7")
    (pin "S8")
    (pin "S9")
    (instances
      (project "d1600e-psu-breakout-board"
        (path ""
          (reference "J10") (unit 1)
        )
      )
    )
  )

  (symbol (lib_id "antmicropower:GND") (at 109.22 80.01 0) (unit 1)
    (in_bom yes) (on_board yes) (dnp no)
    (property "Reference" "#PWR0107" (at 109.22 86.36 0)
      (effects (font (size 1.27 1.27)) hide)
    )
    (property "Value" "GND" (at 109.22 83.82 0)
      (effects (font (size 1.27 1.27) (thickness 0.15)))
    )
    (property "Footprint" "" (at 118.11 87.63 0)
      (effects (font (size 1.27 1.27) (thickness 0.15)) (justify left bottom) hide)
    )
    (property "Datasheet" "" (at 118.11 92.71 0)
      (effects (font (size 1.27 1.27) (thickness 0.15)) (justify left bottom) hide)
    )
    (property "Author" "Antmicro" (at 118.11 87.63 0)
      (effects (font (size 1.27 1.27) (thickness 0.15)) (justify left bottom) hide)
    )
    (property "License" "Apache-2.0" (at 118.11 90.17 0)
      (effects (font (size 1.27 1.27) (thickness 0.15)) (justify left bottom) hide)
    )
    (pin "1")
    (instances
      (project "d1600e-psu-breakout-board"
        (path ""
          (reference "#PWR0107") (unit 1)
        )
      )
    )
  )

  (symbol (lib_id "antmicroTestPoints:TP_1mm_SMD") (at 217.17 162.56 0) (unit 1)
    (in_bom no) (on_board yes) (dnp no) (fields_autoplaced)
    (property "Reference" "TP_S24" (at 222.25 162.56 0)
      (effects (font (size 1.27 1.27)) (justify left))
    )
    (property "Value" "TP_1mm_SMD" (at 232.41 170.18 0)
      (effects (font (size 1.27 1.27) (thickness 0.15)) (justify left bottom) hide)
    )
    (property "Footprint" "antmicro-footprints:TP_SMD_1mm" (at 232.41 172.72 0)
      (effects (font (size 1.27 1.27) (thickness 0.15)) (justify left bottom) hide)
    )
    (property "Datasheet" "" (at 234.95 175.26 0)
      (effects (font (size 1.27 1.27) (thickness 0.15)) (justify left bottom) hide)
    )
    (property "MPN" "" (at 217.17 162.56 0)
      (effects (font (size 1.27 1.27)) hide)
    )
    (property "Manufacturer" "" (at 217.17 162.56 0)
      (effects (font (size 1.27 1.27)) hide)
    )
    (property "Author" "Antmicro" (at 232.41 177.8 0)
      (effects (font (size 1.27 1.27) (thickness 0.15)) (justify left bottom) hide)
    )
    (property "License" "Apache-2.0" (at 232.41 180.34 0)
      (effects (font (size 1.27 1.27) (thickness 0.15)) (justify left bottom) hide)
    )
    (pin "1")
    (instances
      (project "d1600e-psu-breakout-board"
        (path ""
          (reference "TP_S24") (unit 1)
        )
      )
    )
  )

  (symbol (lib_id "antmicroTestPoints:TP_1mm_SMD") (at 217.17 165.1 0) (unit 1)
    (in_bom no) (on_board yes) (dnp no) (fields_autoplaced)
    (property "Reference" "TP_S23" (at 222.25 165.1 0)
      (effects (font (size 1.27 1.27)) (justify left))
    )
    (property "Value" "TP_1mm_SMD" (at 232.41 172.72 0)
      (effects (font (size 1.27 1.27) (thickness 0.15)) (justify left bottom) hide)
    )
    (property "Footprint" "antmicro-footprints:TP_SMD_1mm" (at 232.41 175.26 0)
      (effects (font (size 1.27 1.27) (thickness 0.15)) (justify left bottom) hide)
    )
    (property "Datasheet" "" (at 234.95 177.8 0)
      (effects (font (size 1.27 1.27) (thickness 0.15)) (justify left bottom) hide)
    )
    (property "MPN" "" (at 217.17 165.1 0)
      (effects (font (size 1.27 1.27)) hide)
    )
    (property "Manufacturer" "" (at 217.17 165.1 0)
      (effects (font (size 1.27 1.27)) hide)
    )
    (property "Author" "Antmicro" (at 232.41 180.34 0)
      (effects (font (size 1.27 1.27) (thickness 0.15)) (justify left bottom) hide)
    )
    (property "License" "Apache-2.0" (at 232.41 182.88 0)
      (effects (font (size 1.27 1.27) (thickness 0.15)) (justify left bottom) hide)
    )
    (pin "1")
    (instances
      (project "d1600e-psu-breakout-board"
        (path ""
          (reference "TP_S23") (unit 1)
        )
      )
    )
  )

  (symbol (lib_id "antmicroTestPoints:TP_1mm_SMD") (at 217.17 167.64 0) (unit 1)
    (in_bom no) (on_board yes) (dnp no)
    (property "Reference" "TP_S22" (at 226.06 167.64 0)
      (effects (font (size 1.27 1.27)))
    )
    (property "Value" "TP_1mm_SMD" (at 232.41 175.26 0)
      (effects (font (size 1.27 1.27) (thickness 0.15)) (justify left bottom) hide)
    )
    (property "Footprint" "antmicro-footprints:TP_SMD_1mm" (at 232.41 177.8 0)
      (effects (font (size 1.27 1.27) (thickness 0.15)) (justify left bottom) hide)
    )
    (property "Datasheet" "" (at 234.95 180.34 0)
      (effects (font (size 1.27 1.27) (thickness 0.15)) (justify left bottom) hide)
    )
    (property "MPN" "" (at 217.17 167.64 0)
      (effects (font (size 1.27 1.27)) hide)
    )
    (property "Manufacturer" "" (at 217.17 167.64 0)
      (effects (font (size 1.27 1.27)) hide)
    )
    (property "Author" "Antmicro" (at 232.41 182.88 0)
      (effects (font (size 1.27 1.27) (thickness 0.15)) (justify left bottom) hide)
    )
    (property "License" "Apache-2.0" (at 232.41 185.42 0)
      (effects (font (size 1.27 1.27) (thickness 0.15)) (justify left bottom) hide)
    )
    (pin "1")
    (instances
      (project "d1600e-psu-breakout-board"
        (path ""
          (reference "TP_S22") (unit 1)
        )
      )
    )
  )

  (symbol (lib_id "antmicroTestPoints:TP_1mm_SMD") (at 217.17 170.18 0) (unit 1)
    (in_bom no) (on_board yes) (dnp no) (fields_autoplaced)
    (property "Reference" "TP_S21" (at 222.25 170.18 0)
      (effects (font (size 1.27 1.27)) (justify left))
    )
    (property "Value" "TP_1mm_SMD" (at 232.41 177.8 0)
      (effects (font (size 1.27 1.27) (thickness 0.15)) (justify left bottom) hide)
    )
    (property "Footprint" "antmicro-footprints:TP_SMD_1mm" (at 232.41 180.34 0)
      (effects (font (size 1.27 1.27) (thickness 0.15)) (justify left bottom) hide)
    )
    (property "Datasheet" "" (at 234.95 182.88 0)
      (effects (font (size 1.27 1.27) (thickness 0.15)) (justify left bottom) hide)
    )
    (property "MPN" "" (at 217.17 170.18 0)
      (effects (font (size 1.27 1.27)) hide)
    )
    (property "Manufacturer" "" (at 217.17 170.18 0)
      (effects (font (size 1.27 1.27)) hide)
    )
    (property "Author" "Antmicro" (at 232.41 185.42 0)
      (effects (font (size 1.27 1.27) (thickness 0.15)) (justify left bottom) hide)
    )
    (property "License" "Apache-2.0" (at 232.41 187.96 0)
      (effects (font (size 1.27 1.27) (thickness 0.15)) (justify left bottom) hide)
    )
    (pin "1")
    (instances
      (project "d1600e-psu-breakout-board"
        (path ""
          (reference "TP_S21") (unit 1)
        )
      )
    )
  )

  (symbol (lib_id "antmicroTestPoints:TP_1mm_SMD") (at 217.17 172.72 0) (unit 1)
    (in_bom no) (on_board yes) (dnp no) (fields_autoplaced)
    (property "Reference" "TP_S20" (at 222.25 172.72 0)
      (effects (font (size 1.27 1.27)) (justify left))
    )
    (property "Value" "TP_1mm_SMD" (at 232.41 180.34 0)
      (effects (font (size 1.27 1.27) (thickness 0.15)) (justify left bottom) hide)
    )
    (property "Footprint" "antmicro-footprints:TP_SMD_1mm" (at 232.41 182.88 0)
      (effects (font (size 1.27 1.27) (thickness 0.15)) (justify left bottom) hide)
    )
    (property "Datasheet" "" (at 234.95 185.42 0)
      (effects (font (size 1.27 1.27) (thickness 0.15)) (justify left bottom) hide)
    )
    (property "MPN" "" (at 217.17 172.72 0)
      (effects (font (size 1.27 1.27)) hide)
    )
    (property "Manufacturer" "" (at 217.17 172.72 0)
      (effects (font (size 1.27 1.27)) hide)
    )
    (property "Author" "Antmicro" (at 232.41 187.96 0)
      (effects (font (size 1.27 1.27) (thickness 0.15)) (justify left bottom) hide)
    )
    (property "License" "Apache-2.0" (at 232.41 190.5 0)
      (effects (font (size 1.27 1.27) (thickness 0.15)) (justify left bottom) hide)
    )
    (pin "1")
    (instances
      (project "d1600e-psu-breakout-board"
        (path ""
          (reference "TP_S20") (unit 1)
        )
      )
    )
  )

  (symbol (lib_id "antmicroTestPoints:TP_1mm_SMD") (at 217.17 175.26 0) (unit 1)
    (in_bom no) (on_board yes) (dnp no) (fields_autoplaced)
    (property "Reference" "TP_S19" (at 222.25 175.26 0)
      (effects (font (size 1.27 1.27)) (justify left))
    )
    (property "Value" "TP_1mm_SMD" (at 232.41 182.88 0)
      (effects (font (size 1.27 1.27) (thickness 0.15)) (justify left bottom) hide)
    )
    (property "Footprint" "antmicro-footprints:TP_SMD_1mm" (at 232.41 185.42 0)
      (effects (font (size 1.27 1.27) (thickness 0.15)) (justify left bottom) hide)
    )
    (property "Datasheet" "" (at 234.95 187.96 0)
      (effects (font (size 1.27 1.27) (thickness 0.15)) (justify left bottom) hide)
    )
    (property "MPN" "" (at 217.17 175.26 0)
      (effects (font (size 1.27 1.27)) hide)
    )
    (property "Manufacturer" "" (at 217.17 175.26 0)
      (effects (font (size 1.27 1.27)) hide)
    )
    (property "Author" "Antmicro" (at 232.41 190.5 0)
      (effects (font (size 1.27 1.27) (thickness 0.15)) (justify left bottom) hide)
    )
    (property "License" "Apache-2.0" (at 232.41 193.04 0)
      (effects (font (size 1.27 1.27) (thickness 0.15)) (justify left bottom) hide)
    )
    (pin "1")
    (instances
      (project "d1600e-psu-breakout-board"
        (path ""
          (reference "TP_S19") (unit 1)
        )
      )
    )
  )

  (symbol (lib_id "antmicroTestPoints:TP_1mm_SMD") (at 217.17 177.8 0) (unit 1)
    (in_bom no) (on_board yes) (dnp no) (fields_autoplaced)
    (property "Reference" "TP_S18" (at 222.25 177.8 0)
      (effects (font (size 1.27 1.27)) (justify left))
    )
    (property "Value" "TP_1mm_SMD" (at 232.41 185.42 0)
      (effects (font (size 1.27 1.27) (thickness 0.15)) (justify left bottom) hide)
    )
    (property "Footprint" "antmicro-footprints:TP_SMD_1mm" (at 232.41 187.96 0)
      (effects (font (size 1.27 1.27) (thickness 0.15)) (justify left bottom) hide)
    )
    (property "Datasheet" "" (at 234.95 190.5 0)
      (effects (font (size 1.27 1.27) (thickness 0.15)) (justify left bottom) hide)
    )
    (property "MPN" "" (at 217.17 177.8 0)
      (effects (font (size 1.27 1.27)) hide)
    )
    (property "Manufacturer" "" (at 217.17 177.8 0)
      (effects (font (size 1.27 1.27)) hide)
    )
    (property "Author" "Antmicro" (at 232.41 193.04 0)
      (effects (font (size 1.27 1.27) (thickness 0.15)) (justify left bottom) hide)
    )
    (property "License" "Apache-2.0" (at 232.41 195.58 0)
      (effects (font (size 1.27 1.27) (thickness 0.15)) (justify left bottom) hide)
    )
    (pin "1")
    (instances
      (project "d1600e-psu-breakout-board"
        (path ""
          (reference "TP_S18") (unit 1)
        )
      )
    )
  )

  (symbol (lib_id "antmicroTestPoints:TP_1mm_SMD") (at 217.17 180.34 0) (unit 1)
    (in_bom no) (on_board yes) (dnp no) (fields_autoplaced)
    (property "Reference" "TP_S17" (at 222.25 180.34 0)
      (effects (font (size 1.27 1.27)) (justify left))
    )
    (property "Value" "TP_1mm_SMD" (at 232.41 187.96 0)
      (effects (font (size 1.27 1.27) (thickness 0.15)) (justify left bottom) hide)
    )
    (property "Footprint" "antmicro-footprints:TP_SMD_1mm" (at 232.41 190.5 0)
      (effects (font (size 1.27 1.27) (thickness 0.15)) (justify left bottom) hide)
    )
    (property "Datasheet" "" (at 234.95 193.04 0)
      (effects (font (size 1.27 1.27) (thickness 0.15)) (justify left bottom) hide)
    )
    (property "MPN" "" (at 217.17 180.34 0)
      (effects (font (size 1.27 1.27)) hide)
    )
    (property "Manufacturer" "" (at 217.17 180.34 0)
      (effects (font (size 1.27 1.27)) hide)
    )
    (property "Author" "Antmicro" (at 232.41 195.58 0)
      (effects (font (size 1.27 1.27) (thickness 0.15)) (justify left bottom) hide)
    )
    (property "License" "Apache-2.0" (at 232.41 198.12 0)
      (effects (font (size 1.27 1.27) (thickness 0.15)) (justify left bottom) hide)
    )
    (pin "1")
    (instances
      (project "d1600e-psu-breakout-board"
        (path ""
          (reference "TP_S17") (unit 1)
        )
      )
    )
  )

  (symbol (lib_id "antmicroTestPoints:TP_1mm_SMD") (at 217.17 182.88 0) (unit 1)
    (in_bom no) (on_board yes) (dnp no) (fields_autoplaced)
    (property "Reference" "TP_S16" (at 222.25 182.88 0)
      (effects (font (size 1.27 1.27)) (justify left))
    )
    (property "Value" "TP_1mm_SMD" (at 232.41 190.5 0)
      (effects (font (size 1.27 1.27) (thickness 0.15)) (justify left bottom) hide)
    )
    (property "Footprint" "antmicro-footprints:TP_SMD_1mm" (at 232.41 193.04 0)
      (effects (font (size 1.27 1.27) (thickness 0.15)) (justify left bottom) hide)
    )
    (property "Datasheet" "" (at 234.95 195.58 0)
      (effects (font (size 1.27 1.27) (thickness 0.15)) (justify left bottom) hide)
    )
    (property "MPN" "" (at 217.17 182.88 0)
      (effects (font (size 1.27 1.27)) hide)
    )
    (property "Manufacturer" "" (at 217.17 182.88 0)
      (effects (font (size 1.27 1.27)) hide)
    )
    (property "Author" "Antmicro" (at 232.41 198.12 0)
      (effects (font (size 1.27 1.27) (thickness 0.15)) (justify left bottom) hide)
    )
    (property "License" "Apache-2.0" (at 232.41 200.66 0)
      (effects (font (size 1.27 1.27) (thickness 0.15)) (justify left bottom) hide)
    )
    (pin "1")
    (instances
      (project "d1600e-psu-breakout-board"
        (path ""
          (reference "TP_S16") (unit 1)
        )
      )
    )
  )

  (symbol (lib_id "antmicropower:GND") (at 332.74 226.06 0) (unit 1)
    (in_bom yes) (on_board yes) (dnp no)
    (property "Reference" "#PWR0106" (at 332.74 232.41 0)
      (effects (font (size 1.27 1.27)) hide)
    )
    (property "Value" "GND" (at 332.74 229.87 0)
      (effects (font (size 1.27 1.27) (thickness 0.15)))
    )
    (property "Footprint" "" (at 341.63 233.68 0)
      (effects (font (size 1.27 1.27) (thickness 0.15)) (justify left bottom) hide)
    )
    (property "Datasheet" "" (at 341.63 238.76 0)
      (effects (font (size 1.27 1.27) (thickness 0.15)) (justify left bottom) hide)
    )
    (property "Author" "Antmicro" (at 341.63 233.68 0)
      (effects (font (size 1.27 1.27) (thickness 0.15)) (justify left bottom) hide)
    )
    (property "License" "Apache-2.0" (at 341.63 236.22 0)
      (effects (font (size 1.27 1.27) (thickness 0.15)) (justify left bottom) hide)
    )
    (pin "1")
    (instances
      (project "d1600e-psu-breakout-board"
        (path ""
          (reference "#PWR0106") (unit 1)
        )
      )
    )
  )

  (symbol (lib_id "antmicroTestPoints:TP_1mm_SMD") (at 179.07 162.56 180) (unit 1)
    (in_bom no) (on_board yes) (dnp no)
    (property "Reference" "TP_S1" (at 171.45 162.56 0)
      (effects (font (size 1.27 1.27)))
    )
    (property "Value" "TP_1mm_SMD" (at 163.83 154.94 0)
      (effects (font (size 1.27 1.27) (thickness 0.15)) (justify left bottom) hide)
    )
    (property "Footprint" "antmicro-footprints:TP_SMD_1mm" (at 163.83 152.4 0)
      (effects (font (size 1.27 1.27) (thickness 0.15)) (justify left bottom) hide)
    )
    (property "Datasheet" "" (at 161.29 149.86 0)
      (effects (font (size 1.27 1.27) (thickness 0.15)) (justify left bottom) hide)
    )
    (property "MPN" "" (at 179.07 162.56 0)
      (effects (font (size 1.27 1.27)) hide)
    )
    (property "Manufacturer" "" (at 179.07 162.56 0)
      (effects (font (size 1.27 1.27)) hide)
    )
    (property "Author" "Antmicro" (at 163.83 147.32 0)
      (effects (font (size 1.27 1.27) (thickness 0.15)) (justify left bottom) hide)
    )
    (property "License" "Apache-2.0" (at 163.83 144.78 0)
      (effects (font (size 1.27 1.27) (thickness 0.15)) (justify left bottom) hide)
    )
    (pin "1")
    (instances
      (project "d1600e-psu-breakout-board"
        (path ""
          (reference "TP_S1") (unit 1)
        )
      )
    )
  )

  (symbol (lib_id "antmicropower:GND") (at 232.41 158.75 0) (unit 1)
    (in_bom yes) (on_board yes) (dnp no)
    (property "Reference" "#PWR0105" (at 232.41 165.1 0)
      (effects (font (size 1.27 1.27)) hide)
    )
    (property "Value" "GND" (at 232.41 162.56 0)
      (effects (font (size 1.27 1.27) (thickness 0.15)))
    )
    (property "Footprint" "" (at 241.3 166.37 0)
      (effects (font (size 1.27 1.27) (thickness 0.15)) (justify left bottom) hide)
    )
    (property "Datasheet" "" (at 241.3 171.45 0)
      (effects (font (size 1.27 1.27) (thickness 0.15)) (justify left bottom) hide)
    )
    (property "Author" "Antmicro" (at 241.3 166.37 0)
      (effects (font (size 1.27 1.27) (thickness 0.15)) (justify left bottom) hide)
    )
    (property "License" "Apache-2.0" (at 241.3 168.91 0)
      (effects (font (size 1.27 1.27) (thickness 0.15)) (justify left bottom) hide)
    )
    (pin "1")
    (instances
      (project "d1600e-psu-breakout-board"
        (path ""
          (reference "#PWR0105") (unit 1)
        )
      )
    )
  )

  (symbol (lib_id "antmicroTestPoints:TP_1mm_SMD") (at 179.07 165.1 180) (unit 1)
    (in_bom no) (on_board yes) (dnp no)
    (property "Reference" "TP_S2" (at 171.45 165.1 0)
      (effects (font (size 1.27 1.27)))
    )
    (property "Value" "TP_1mm_SMD" (at 163.83 157.48 0)
      (effects (font (size 1.27 1.27) (thickness 0.15)) (justify left bottom) hide)
    )
    (property "Footprint" "antmicro-footprints:TP_SMD_1mm" (at 163.83 154.94 0)
      (effects (font (size 1.27 1.27) (thickness 0.15)) (justify left bottom) hide)
    )
    (property "Datasheet" "" (at 161.29 152.4 0)
      (effects (font (size 1.27 1.27) (thickness 0.15)) (justify left bottom) hide)
    )
    (property "MPN" "" (at 179.07 165.1 0)
      (effects (font (size 1.27 1.27)) hide)
    )
    (property "Manufacturer" "" (at 179.07 165.1 0)
      (effects (font (size 1.27 1.27)) hide)
    )
    (property "Author" "Antmicro" (at 163.83 149.86 0)
      (effects (font (size 1.27 1.27) (thickness 0.15)) (justify left bottom) hide)
    )
    (property "License" "Apache-2.0" (at 163.83 147.32 0)
      (effects (font (size 1.27 1.27) (thickness 0.15)) (justify left bottom) hide)
    )
    (pin "1")
    (instances
      (project "d1600e-psu-breakout-board"
        (path ""
          (reference "TP_S2") (unit 1)
        )
      )
    )
  )

  (symbol (lib_id "antmicroTestPoints:TP_1mm_SMD") (at 179.07 167.64 180) (unit 1)
    (in_bom no) (on_board yes) (dnp no)
    (property "Reference" "TP_S3" (at 171.45 167.64 0)
      (effects (font (size 1.27 1.27)))
    )
    (property "Value" "TP_1mm_SMD" (at 163.83 160.02 0)
      (effects (font (size 1.27 1.27) (thickness 0.15)) (justify left bottom) hide)
    )
    (property "Footprint" "antmicro-footprints:TP_SMD_1mm" (at 163.83 157.48 0)
      (effects (font (size 1.27 1.27) (thickness 0.15)) (justify left bottom) hide)
    )
    (property "Datasheet" "" (at 161.29 154.94 0)
      (effects (font (size 1.27 1.27) (thickness 0.15)) (justify left bottom) hide)
    )
    (property "MPN" "" (at 179.07 167.64 0)
      (effects (font (size 1.27 1.27)) hide)
    )
    (property "Manufacturer" "" (at 179.07 167.64 0)
      (effects (font (size 1.27 1.27)) hide)
    )
    (property "Author" "Antmicro" (at 163.83 152.4 0)
      (effects (font (size 1.27 1.27) (thickness 0.15)) (justify left bottom) hide)
    )
    (property "License" "Apache-2.0" (at 163.83 149.86 0)
      (effects (font (size 1.27 1.27) (thickness 0.15)) (justify left bottom) hide)
    )
    (pin "1")
    (instances
      (project "d1600e-psu-breakout-board"
        (path ""
          (reference "TP_S3") (unit 1)
        )
      )
    )
  )

  (symbol (lib_id "antmicroTestPoints:TP_1mm_SMD") (at 179.07 170.18 180) (unit 1)
    (in_bom no) (on_board yes) (dnp no)
    (property "Reference" "TP_S4" (at 171.45 170.18 0)
      (effects (font (size 1.27 1.27)))
    )
    (property "Value" "TP_1mm_SMD" (at 163.83 162.56 0)
      (effects (font (size 1.27 1.27) (thickness 0.15)) (justify left bottom) hide)
    )
    (property "Footprint" "antmicro-footprints:TP_SMD_1mm" (at 163.83 160.02 0)
      (effects (font (size 1.27 1.27) (thickness 0.15)) (justify left bottom) hide)
    )
    (property "Datasheet" "" (at 161.29 157.48 0)
      (effects (font (size 1.27 1.27) (thickness 0.15)) (justify left bottom) hide)
    )
    (property "MPN" "" (at 179.07 170.18 0)
      (effects (font (size 1.27 1.27)) hide)
    )
    (property "Manufacturer" "" (at 179.07 170.18 0)
      (effects (font (size 1.27 1.27)) hide)
    )
    (property "Author" "Antmicro" (at 163.83 154.94 0)
      (effects (font (size 1.27 1.27) (thickness 0.15)) (justify left bottom) hide)
    )
    (property "License" "Apache-2.0" (at 163.83 152.4 0)
      (effects (font (size 1.27 1.27) (thickness 0.15)) (justify left bottom) hide)
    )
    (pin "1")
    (instances
      (project "d1600e-psu-breakout-board"
        (path ""
          (reference "TP_S4") (unit 1)
        )
      )
    )
  )

  (symbol (lib_id "antmicroTestPoints:TP_1mm_SMD") (at 179.07 172.72 180) (unit 1)
    (in_bom no) (on_board yes) (dnp no)
    (property "Reference" "TP_S5" (at 171.45 172.72 0)
      (effects (font (size 1.27 1.27)))
    )
    (property "Value" "TP_1mm_SMD" (at 163.83 165.1 0)
      (effects (font (size 1.27 1.27) (thickness 0.15)) (justify left bottom) hide)
    )
    (property "Footprint" "antmicro-footprints:TP_SMD_1mm" (at 163.83 162.56 0)
      (effects (font (size 1.27 1.27) (thickness 0.15)) (justify left bottom) hide)
    )
    (property "Datasheet" "" (at 161.29 160.02 0)
      (effects (font (size 1.27 1.27) (thickness 0.15)) (justify left bottom) hide)
    )
    (property "MPN" "" (at 179.07 172.72 0)
      (effects (font (size 1.27 1.27)) hide)
    )
    (property "Manufacturer" "" (at 179.07 172.72 0)
      (effects (font (size 1.27 1.27)) hide)
    )
    (property "Author" "Antmicro" (at 163.83 157.48 0)
      (effects (font (size 1.27 1.27) (thickness 0.15)) (justify left bottom) hide)
    )
    (property "License" "Apache-2.0" (at 163.83 154.94 0)
      (effects (font (size 1.27 1.27) (thickness 0.15)) (justify left bottom) hide)
    )
    (pin "1")
    (instances
      (project "d1600e-psu-breakout-board"
        (path ""
          (reference "TP_S5") (unit 1)
        )
      )
    )
  )

  (symbol (lib_id "antmicroTestPoints:TP_1mm_SMD") (at 179.07 175.26 180) (unit 1)
    (in_bom no) (on_board yes) (dnp no)
    (property "Reference" "TP_S6" (at 171.45 175.26 0)
      (effects (font (size 1.27 1.27)))
    )
    (property "Value" "TP_1mm_SMD" (at 163.83 167.64 0)
      (effects (font (size 1.27 1.27) (thickness 0.15)) (justify left bottom) hide)
    )
    (property "Footprint" "antmicro-footprints:TP_SMD_1mm" (at 163.83 165.1 0)
      (effects (font (size 1.27 1.27) (thickness 0.15)) (justify left bottom) hide)
    )
    (property "Datasheet" "" (at 161.29 162.56 0)
      (effects (font (size 1.27 1.27) (thickness 0.15)) (justify left bottom) hide)
    )
    (property "MPN" "" (at 179.07 175.26 0)
      (effects (font (size 1.27 1.27)) hide)
    )
    (property "Manufacturer" "" (at 179.07 175.26 0)
      (effects (font (size 1.27 1.27)) hide)
    )
    (property "Author" "Antmicro" (at 163.83 160.02 0)
      (effects (font (size 1.27 1.27) (thickness 0.15)) (justify left bottom) hide)
    )
    (property "License" "Apache-2.0" (at 163.83 157.48 0)
      (effects (font (size 1.27 1.27) (thickness 0.15)) (justify left bottom) hide)
    )
    (pin "1")
    (instances
      (project "d1600e-psu-breakout-board"
        (path ""
          (reference "TP_S6") (unit 1)
        )
      )
    )
  )

  (symbol (lib_id "antmicroTestPoints:TP_1mm_SMD") (at 179.07 177.8 180) (unit 1)
    (in_bom no) (on_board yes) (dnp no)
    (property "Reference" "TP_S7" (at 171.45 177.8 0)
      (effects (font (size 1.27 1.27)))
    )
    (property "Value" "TP_1mm_SMD" (at 163.83 170.18 0)
      (effects (font (size 1.27 1.27) (thickness 0.15)) (justify left bottom) hide)
    )
    (property "Footprint" "antmicro-footprints:TP_SMD_1mm" (at 163.83 167.64 0)
      (effects (font (size 1.27 1.27) (thickness 0.15)) (justify left bottom) hide)
    )
    (property "Datasheet" "" (at 161.29 165.1 0)
      (effects (font (size 1.27 1.27) (thickness 0.15)) (justify left bottom) hide)
    )
    (property "MPN" "" (at 179.07 177.8 0)
      (effects (font (size 1.27 1.27)) hide)
    )
    (property "Manufacturer" "" (at 179.07 177.8 0)
      (effects (font (size 1.27 1.27)) hide)
    )
    (property "Author" "Antmicro" (at 163.83 162.56 0)
      (effects (font (size 1.27 1.27) (thickness 0.15)) (justify left bottom) hide)
    )
    (property "License" "Apache-2.0" (at 163.83 160.02 0)
      (effects (font (size 1.27 1.27) (thickness 0.15)) (justify left bottom) hide)
    )
    (pin "1")
    (instances
      (project "d1600e-psu-breakout-board"
        (path ""
          (reference "TP_S7") (unit 1)
        )
      )
    )
  )

  (symbol (lib_id "antmicroTestPoints:TP_1mm_SMD") (at 179.07 180.34 180) (unit 1)
    (in_bom no) (on_board yes) (dnp no)
    (property "Reference" "TP_S8" (at 171.45 180.34 0)
      (effects (font (size 1.27 1.27)))
    )
    (property "Value" "TP_1mm_SMD" (at 163.83 172.72 0)
      (effects (font (size 1.27 1.27) (thickness 0.15)) (justify left bottom) hide)
    )
    (property "Footprint" "antmicro-footprints:TP_SMD_1mm" (at 163.83 170.18 0)
      (effects (font (size 1.27 1.27) (thickness 0.15)) (justify left bottom) hide)
    )
    (property "Datasheet" "" (at 161.29 167.64 0)
      (effects (font (size 1.27 1.27) (thickness 0.15)) (justify left bottom) hide)
    )
    (property "MPN" "" (at 179.07 180.34 0)
      (effects (font (size 1.27 1.27)) hide)
    )
    (property "Manufacturer" "" (at 179.07 180.34 0)
      (effects (font (size 1.27 1.27)) hide)
    )
    (property "Author" "Antmicro" (at 163.83 165.1 0)
      (effects (font (size 1.27 1.27) (thickness 0.15)) (justify left bottom) hide)
    )
    (property "License" "Apache-2.0" (at 163.83 162.56 0)
      (effects (font (size 1.27 1.27) (thickness 0.15)) (justify left bottom) hide)
    )
    (pin "1")
    (instances
      (project "d1600e-psu-breakout-board"
        (path ""
          (reference "TP_S8") (unit 1)
        )
      )
    )
  )

  (symbol (lib_id "antmicroTestPoints:TP_1mm_SMD") (at 179.07 182.88 180) (unit 1)
    (in_bom no) (on_board yes) (dnp no)
    (property "Reference" "TP_S9" (at 171.45 182.88 0)
      (effects (font (size 1.27 1.27)))
    )
    (property "Value" "TP_1mm_SMD" (at 163.83 175.26 0)
      (effects (font (size 1.27 1.27) (thickness 0.15)) (justify left bottom) hide)
    )
    (property "Footprint" "antmicro-footprints:TP_SMD_1mm" (at 163.83 172.72 0)
      (effects (font (size 1.27 1.27) (thickness 0.15)) (justify left bottom) hide)
    )
    (property "Datasheet" "" (at 161.29 170.18 0)
      (effects (font (size 1.27 1.27) (thickness 0.15)) (justify left bottom) hide)
    )
    (property "MPN" "" (at 179.07 182.88 0)
      (effects (font (size 1.27 1.27)) hide)
    )
    (property "Manufacturer" "" (at 179.07 182.88 0)
      (effects (font (size 1.27 1.27)) hide)
    )
    (property "Author" "Antmicro" (at 163.83 167.64 0)
      (effects (font (size 1.27 1.27) (thickness 0.15)) (justify left bottom) hide)
    )
    (property "License" "Apache-2.0" (at 163.83 165.1 0)
      (effects (font (size 1.27 1.27) (thickness 0.15)) (justify left bottom) hide)
    )
    (pin "1")
    (instances
      (project "d1600e-psu-breakout-board"
        (path ""
          (reference "TP_S9") (unit 1)
        )
      )
    )
  )

  (symbol (lib_id "antmicroTestPoints:TP_1mm_SMD") (at 179.07 185.42 180) (unit 1)
    (in_bom no) (on_board yes) (dnp no)
    (property "Reference" "TP_S10" (at 171.45 185.42 0)
      (effects (font (size 1.27 1.27)))
    )
    (property "Value" "TP_1mm_SMD" (at 163.83 177.8 0)
      (effects (font (size 1.27 1.27) (thickness 0.15)) (justify left bottom) hide)
    )
    (property "Footprint" "antmicro-footprints:TP_SMD_1mm" (at 163.83 175.26 0)
      (effects (font (size 1.27 1.27) (thickness 0.15)) (justify left bottom) hide)
    )
    (property "Datasheet" "" (at 161.29 172.72 0)
      (effects (font (size 1.27 1.27) (thickness 0.15)) (justify left bottom) hide)
    )
    (property "MPN" "" (at 179.07 185.42 0)
      (effects (font (size 1.27 1.27)) hide)
    )
    (property "Manufacturer" "" (at 179.07 185.42 0)
      (effects (font (size 1.27 1.27)) hide)
    )
    (property "Author" "Antmicro" (at 163.83 170.18 0)
      (effects (font (size 1.27 1.27) (thickness 0.15)) (justify left bottom) hide)
    )
    (property "License" "Apache-2.0" (at 163.83 167.64 0)
      (effects (font (size 1.27 1.27) (thickness 0.15)) (justify left bottom) hide)
    )
    (pin "1")
    (instances
      (project "d1600e-psu-breakout-board"
        (path ""
          (reference "TP_S10") (unit 1)
        )
      )
    )
  )

  (symbol (lib_id "antmicroTestPoints:TP_1mm_SMD") (at 179.07 187.96 180) (unit 1)
    (in_bom no) (on_board yes) (dnp no)
    (property "Reference" "TP_S11" (at 171.45 187.96 0)
      (effects (font (size 1.27 1.27)))
    )
    (property "Value" "TP_1mm_SMD" (at 163.83 180.34 0)
      (effects (font (size 1.27 1.27) (thickness 0.15)) (justify left bottom) hide)
    )
    (property "Footprint" "antmicro-footprints:TP_SMD_1mm" (at 163.83 177.8 0)
      (effects (font (size 1.27 1.27) (thickness 0.15)) (justify left bottom) hide)
    )
    (property "Datasheet" "" (at 161.29 175.26 0)
      (effects (font (size 1.27 1.27) (thickness 0.15)) (justify left bottom) hide)
    )
    (property "MPN" "" (at 179.07 187.96 0)
      (effects (font (size 1.27 1.27)) hide)
    )
    (property "Manufacturer" "" (at 179.07 187.96 0)
      (effects (font (size 1.27 1.27)) hide)
    )
    (property "Author" "Antmicro" (at 163.83 172.72 0)
      (effects (font (size 1.27 1.27) (thickness 0.15)) (justify left bottom) hide)
    )
    (property "License" "Apache-2.0" (at 163.83 170.18 0)
      (effects (font (size 1.27 1.27) (thickness 0.15)) (justify left bottom) hide)
    )
    (pin "1")
    (instances
      (project "d1600e-psu-breakout-board"
        (path ""
          (reference "TP_S11") (unit 1)
        )
      )
    )
  )

  (symbol (lib_id "antmicroTestPoints:TP_1mm_SMD") (at 179.07 190.5 180) (unit 1)
    (in_bom no) (on_board yes) (dnp no)
    (property "Reference" "TP_S12" (at 171.45 190.5 0)
      (effects (font (size 1.27 1.27)))
    )
    (property "Value" "TP_1mm_SMD" (at 163.83 182.88 0)
      (effects (font (size 1.27 1.27) (thickness 0.15)) (justify left bottom) hide)
    )
    (property "Footprint" "antmicro-footprints:TP_SMD_1mm" (at 163.83 180.34 0)
      (effects (font (size 1.27 1.27) (thickness 0.15)) (justify left bottom) hide)
    )
    (property "Datasheet" "" (at 161.29 177.8 0)
      (effects (font (size 1.27 1.27) (thickness 0.15)) (justify left bottom) hide)
    )
    (property "MPN" "" (at 179.07 190.5 0)
      (effects (font (size 1.27 1.27)) hide)
    )
    (property "Manufacturer" "" (at 179.07 190.5 0)
      (effects (font (size 1.27 1.27)) hide)
    )
    (property "Author" "Antmicro" (at 163.83 175.26 0)
      (effects (font (size 1.27 1.27) (thickness 0.15)) (justify left bottom) hide)
    )
    (property "License" "Apache-2.0" (at 163.83 172.72 0)
      (effects (font (size 1.27 1.27) (thickness 0.15)) (justify left bottom) hide)
    )
    (pin "1")
    (instances
      (project "d1600e-psu-breakout-board"
        (path ""
          (reference "TP_S12") (unit 1)
        )
      )
    )
  )

  (symbol (lib_id "antmicroLEDIndicationDiscrete:LED_G_0603_LG_L29K-G2J1-24-Z") (at 222.25 80.01 90) (unit 1)
    (in_bom yes) (on_board yes) (dnp no) (fields_autoplaced)
    (property "Reference" "D5" (at 224.79 76.2 90)
      (effects (font (size 1.27 1.27)) (justify right))
    )
    (property "Value" "LED_G_0603_LG_L29K-G2J1-24-Z" (at 229.87 59.69 0)
      (effects (font (size 1.27 1.27) (thickness 0.15)) (justify left bottom) hide)
    )
    (property "Footprint" "antmicro-footprints:LED_0603_1608Metric_G" (at 232.41 59.69 0)
      (effects (font (size 1.27 1.27) (thickness 0.15)) (justify left bottom) hide)
    )
    (property "Datasheet" "https://look.ams-osram.com/m/19ee86b3ae0ee95b/original/LG-L29K.pdf" (at 234.95 59.69 0)
      (effects (font (size 1.27 1.27) (thickness 0.15)) (justify left bottom) hide)
    )
    (property "MPN" "LG L29K-G2J1-24-Z" (at 237.49 59.69 0)
      (effects (font (size 1.27 1.27) (thickness 0.15)) (justify left bottom) hide)
    )
    (property "Manufacturer" "OSRAM" (at 240.03 59.69 0)
      (effects (font (size 1.27 1.27) (thickness 0.15)) (justify left bottom) hide)
    )
    (property "Color" "Green" (at 224.79 78.74 90)
      (effects (font (size 1.27 1.27)) (justify right))
    )
    (property "Author" "Antmicro" (at 242.57 59.69 0)
      (effects (font (size 1.27 1.27) (thickness 0.15)) (justify left bottom) hide)
    )
    (property "License" "Apache-2.0" (at 245.11 59.69 0)
      (effects (font (size 1.27 1.27) (thickness 0.15)) (justify left bottom) hide)
    )
    (pin "1")
    (pin "2")
    (instances
      (project "d1600e-psu-breakout-board"
        (path ""
          (reference "D5") (unit 1)
        )
      )
    )
  )

  (symbol (lib_id "antmicropower:GND") (at 222.25 92.71 0) (unit 1)
    (in_bom yes) (on_board yes) (dnp no)
    (property "Reference" "#PWR071" (at 222.25 99.06 0)
      (effects (font (size 1.27 1.27)) hide)
    )
    (property "Value" "GND" (at 222.25 96.52 0)
      (effects (font (size 1.27 1.27) (thickness 0.15)))
    )
    (property "Footprint" "" (at 231.14 100.33 0)
      (effects (font (size 1.27 1.27) (thickness 0.15)) (justify left bottom) hide)
    )
    (property "Datasheet" "" (at 231.14 105.41 0)
      (effects (font (size 1.27 1.27) (thickness 0.15)) (justify left bottom) hide)
    )
    (property "Author" "Antmicro" (at 231.14 100.33 0)
      (effects (font (size 1.27 1.27) (thickness 0.15)) (justify left bottom) hide)
    )
    (property "License" "Apache-2.0" (at 231.14 102.87 0)
      (effects (font (size 1.27 1.27) (thickness 0.15)) (justify left bottom) hide)
    )
    (pin "1")
    (instances
      (project "d1600e-psu-breakout-board"
        (path ""
          (reference "#PWR071") (unit 1)
        )
      )
    )
  )

  (symbol (lib_id "antmicroResistors0402:R_10k_0402") (at 208.28 67.31 180) (unit 1)
    (in_bom yes) (on_board yes) (dnp no)
    (property "Reference" "R40" (at 205.74 62.23 0)
      (effects (font (size 1.27 1.27)))
    )
    (property "Value" "R_10k_0402" (at 187.96 54.61 0)
      (effects (font (size 1.27 1.27) (thickness 0.15)) (justify left bottom) hide)
    )
    (property "Footprint" "antmicro-footprints:R_0402_1005Metric" (at 187.96 52.07 0)
      (effects (font (size 1.27 1.27) (thickness 0.15)) (justify left bottom) hide)
    )
    (property "Datasheet" "https://www.bourns.com/docs/product-datasheets/cr.pdf" (at 187.96 49.53 0)
      (effects (font (size 1.27 1.27) (thickness 0.15)) (justify left bottom) hide)
    )
    (property "Manufacturer" "Bourns" (at 187.96 44.45 0)
      (effects (font (size 1.27 1.27) (thickness 0.15)) (justify left bottom) hide)
    )
    (property "MPN" "CR0402-FX-1002GLF" (at 187.96 46.99 0)
      (effects (font (size 1.27 1.27) (thickness 0.15)) (justify left bottom) hide)
    )
    (property "Val" "10k" (at 205.74 64.77 0)
      (effects (font (size 1.27 1.27) (thickness 0.15)))
    )
    (property "License" "Apache-2.0" (at 187.96 41.91 0)
      (effects (font (size 1.27 1.27) (thickness 0.15)) (justify left bottom) hide)
    )
    (property "Author" "Antmicro" (at 187.96 39.37 0)
      (effects (font (size 1.27 1.27) (thickness 0.15)) (justify left bottom) hide)
    )
    (property "Tolerance" "1%" (at 187.96 57.15 0)
      (effects (font (size 1.27 1.27)) (justify left bottom) hide)
    )
    (pin "1")
    (pin "2")
    (instances
      (project "d1600e-psu-breakout-board"
        (path ""
          (reference "R40") (unit 1)
        )
      )
    )
  )

  (symbol (lib_id "antmicroTestPoints:TP_1mm_SMD") (at 222.25 189.23 270) (unit 1)
    (in_bom no) (on_board yes) (dnp no)
    (property "Reference" "TP_S_ON1" (at 223.52 192.405 90)
      (effects (font (size 1.27 1.27)) (justify left))
    )
    (property "Value" "TP_1mm_SMD" (at 214.63 204.47 0)
      (effects (font (size 1.27 1.27) (thickness 0.15)) (justify left bottom) hide)
    )
    (property "Footprint" "antmicro-footprints:TP_SMD_1mm" (at 212.09 204.47 0)
      (effects (font (size 1.27 1.27) (thickness 0.15)) (justify left bottom) hide)
    )
    (property "Datasheet" "" (at 209.55 207.01 0)
      (effects (font (size 1.27 1.27) (thickness 0.15)) (justify left bottom) hide)
    )
    (property "MPN" "" (at 222.25 189.23 0)
      (effects (font (size 1.27 1.27)) hide)
    )
    (property "Manufacturer" "" (at 222.25 189.23 0)
      (effects (font (size 1.27 1.27)) hide)
    )
    (property "Author" "Antmicro" (at 207.01 204.47 0)
      (effects (font (size 1.27 1.27) (thickness 0.15)) (justify left bottom) hide)
    )
    (property "License" "Apache-2.0" (at 204.47 204.47 0)
      (effects (font (size 1.27 1.27) (thickness 0.15)) (justify left bottom) hide)
    )
    (pin "1")
    (instances
      (project "d1600e-psu-breakout-board"
        (path ""
          (reference "TP_S_ON1") (unit 1)
        )
      )
    )
  )

  (symbol (lib_id "antmicroResistors0402:R_680R_0402") (at 222.25 83.82 270) (unit 1)
    (in_bom yes) (on_board yes) (dnp no)
    (property "Reference" "R41" (at 223.52 85.09 90)
      (effects (font (size 1.27 1.27)) (justify left))
    )
    (property "Value" "R_680R_0402" (at 209.55 104.14 0)
      (effects (font (size 1.27 1.27) (thickness 0.15)) (justify left bottom) hide)
    )
    (property "Footprint" "antmicro-footprints:R_0402_1005Metric" (at 207.01 104.14 0)
      (effects (font (size 1.27 1.27) (thickness 0.15)) (justify left bottom) hide)
    )
    (property "Datasheet" "https://www.bourns.com/docs/product-datasheets/cr.pdf" (at 204.47 104.14 0)
      (effects (font (size 1.27 1.27) (thickness 0.15)) (justify left bottom) hide)
    )
    (property "Manufacturer" "Bourns" (at 199.39 104.14 0)
      (effects (font (size 1.27 1.27) (thickness 0.15)) (justify left bottom) hide)
    )
    (property "MPN" "CR0402-FX-6800GLF" (at 201.93 104.14 0)
      (effects (font (size 1.27 1.27) (thickness 0.15)) (justify left bottom) hide)
    )
    (property "Val" "680R" (at 223.52 87.63 90)
      (effects (font (size 1.27 1.27) (thickness 0.15)) (justify left))
    )
    (property "License" "Apache-2.0" (at 196.85 104.14 0)
      (effects (font (size 1.27 1.27) (thickness 0.15)) (justify left bottom) hide)
    )
    (property "Author" "Antmicro" (at 194.31 104.14 0)
      (effects (font (size 1.27 1.27) (thickness 0.15)) (justify left bottom) hide)
    )
    (property "Tolerance" "1%" (at 212.09 104.14 0)
      (effects (font (size 1.27 1.27)) (justify left bottom) hide)
    )
    (pin "1")
    (pin "2")
    (instances
      (project "d1600e-psu-breakout-board"
        (path ""
          (reference "R41") (unit 1)
        )
      )
    )
  )

  (symbol (lib_id "antmicroResistors0402:R_0R_0402") (at 201.93 88.9 180) (unit 1)
    (in_bom no) (on_board yes) (dnp yes)
    (property "Reference" "R45" (at 199.39 83.82 0)
      (effects (font (size 1.27 1.27)))
    )
    (property "Value" "R_0R_0402" (at 181.61 76.2 0)
      (effects (font (size 1.27 1.27) (thickness 0.15)) (justify left bottom) hide)
    )
    (property "Footprint" "antmicro-footprints:R_0402_1005Metric" (at 181.61 73.66 0)
      (effects (font (size 1.27 1.27) (thickness 0.15)) (justify left bottom) hide)
    )
    (property "Datasheet" "https://industrial.panasonic.com/cdbs/www-data/pdf/RDA0000/AOA0000C301.pdf" (at 181.61 71.12 0)
      (effects (font (size 1.27 1.27) (thickness 0.15)) (justify left bottom) hide)
    )
    (property "Manufacturer" "Panasonic" (at 181.61 66.04 0)
      (effects (font (size 1.27 1.27) (thickness 0.15)) (justify left bottom) hide)
    )
    (property "MPN" "ERJ2GE0R00X" (at 181.61 68.58 0)
      (effects (font (size 1.27 1.27) (thickness 0.15)) (justify left bottom) hide)
    )
    (property "Val" "0R" (at 199.39 86.36 0)
      (effects (font (size 1.27 1.27) (thickness 0.15)))
    )
    (property "DNP" "DNP" (at 199.39 91.44 0)
      (effects (font (size 1.27 1.27)))
    )
    (property "License" "Apache-2.0" (at 181.61 63.5 0)
      (effects (font (size 1.27 1.27) (thickness 0.15)) (justify left bottom) hide)
    )
    (property "Author" "Antmicro" (at 181.61 60.96 0)
      (effects (font (size 1.27 1.27) (thickness 0.15)) (justify left bottom) hide)
    )
    (property "Tolerance" "~" (at 181.61 78.74 0)
      (effects (font (size 1.27 1.27)) (justify left bottom) hide)
    )
    (property "Current" "1A" (at 181.61 58.42 0)
      (effects (font (size 1.27 1.27) (thickness 0.15)) (justify left bottom) hide)
    )
    (pin "1")
    (pin "2")
    (instances
      (project "d1600e-psu-breakout-board"
        (path ""
          (reference "R45") (unit 1)
        )
      )
    )
  )

  (symbol (lib_id "antmicropower:GND") (at 209.55 92.71 0) (unit 1)
    (in_bom yes) (on_board yes) (dnp no)
    (property "Reference" "#PWR0102" (at 209.55 99.06 0)
      (effects (font (size 1.27 1.27)) hide)
    )
    (property "Value" "GND" (at 209.55 96.52 0)
      (effects (font (size 1.27 1.27) (thickness 0.15)))
    )
    (property "Footprint" "" (at 218.44 100.33 0)
      (effects (font (size 1.27 1.27) (thickness 0.15)) (justify left bottom) hide)
    )
    (property "Datasheet" "" (at 218.44 105.41 0)
      (effects (font (size 1.27 1.27) (thickness 0.15)) (justify left bottom) hide)
    )
    (property "Author" "Antmicro" (at 218.44 100.33 0)
      (effects (font (size 1.27 1.27) (thickness 0.15)) (justify left bottom) hide)
    )
    (property "License" "Apache-2.0" (at 218.44 102.87 0)
      (effects (font (size 1.27 1.27) (thickness 0.15)) (justify left bottom) hide)
    )
    (pin "1")
    (instances
      (project "d1600e-psu-breakout-board"
        (path ""
          (reference "#PWR0102") (unit 1)
        )
      )
    )
  )

  (symbol (lib_id "antmicroMechanicalParts:MP_Pad6mm_Drill3.2mm") (at 335.28 215.9 0) (unit 1)
    (in_bom no) (on_board yes) (dnp no) (fields_autoplaced)
    (property "Reference" "MP3" (at 344.17 214.63 0)
      (effects (font (size 1.27 1.27) (thickness 0.15)) (justify left))
    )
    (property "Value" "MP_Pad6mm_Drill3.2mm" (at 344.17 217.17 0)
      (effects (font (size 1.27 1.27) (thickness 0.15)) (justify left))
    )
    (property "Footprint" "antmicro-footprints:MP_Pad6mm_Drill3.2mm" (at 355.6 223.52 0)
      (effects (font (size 1.27 1.27) (thickness 0.15)) (justify left bottom) hide)
    )
    (property "Datasheet" "" (at 352.12 231.47 0)
      (effects (font (size 1.27 1.27) (thickness 0.15)) (justify left bottom) hide)
    )
    (property "Author" "Antmicro" (at 355.6 226.06 0)
      (effects (font (size 1.27 1.27) (thickness 0.15)) (justify left bottom) hide)
    )
    (property "License" "Apache-2.0" (at 355.6 228.6 0)
      (effects (font (size 1.27 1.27) (thickness 0.15)) (justify left bottom) hide)
    )
    (pin "1")
    (instances
      (project "d1600e-psu-breakout-board"
        (path ""
          (reference "MP3") (unit 1)
        )
      )
    )
  )

  (symbol (lib_id "antmicroWire2BoardConnectors:Molex_KK_1x4_22-27-2041") (at 46.99 209.55 0) (mirror x) (unit 1)
    (in_bom yes) (on_board yes) (dnp no)
    (property "Reference" "J1" (at 53.34 207.01 0)
      (effects (font (size 1.27 1.27) (thickness 0.15)) (justify left))
    )
    (property "Value" "Molex_KK_1x4_22-27-2041" (at 60.325 204.47 0)
      (effects (font (size 1.27 1.27) (thickness 0.15)) (justify left bottom) hide)
    )
    (property "Footprint" "antmicro-footprints:Conn_Molex_KK_1x4_22-27-2041" (at 60.325 201.93 0)
      (effects (font (size 1.27 1.27) (thickness 0.15)) (justify left bottom) hide)
    )
    (property "Datasheet" "https://www.molex.com/en-us/products/part-detail/22272041?display=pdf" (at 60.325 199.39 0)
      (effects (font (size 1.27 1.27) (thickness 0.15)) (justify left bottom) hide)
    )
    (property "MPN" "22-27-2041" (at 53.34 204.47 0)
      (effects (font (size 1.27 1.27) (thickness 0.15)) (justify left))
    )
    (property "Manufacturer" "Molex" (at 60.325 194.31 0)
      (effects (font (size 1.27 1.27) (thickness 0.15)) (justify left bottom) hide)
    )
    (property "Author" "Antmicro" (at 60.325 191.77 0)
      (effects (font (size 1.27 1.27) (thickness 0.15)) (justify left bottom) hide)
    )
    (property "License" "Apache-2.0" (at 60.325 189.23 0)
      (effects (font (size 1.27 1.27) (thickness 0.15)) (justify left bottom) hide)
    )
    (pin "3")
    (pin "1")
    (pin "2")
    (pin "4")
    (instances
      (project "d1600e-psu-breakout-board"
        (path ""
          (reference "J1") (unit 1)
        )
      )
    )
  )

  (symbol (lib_id "antmicropower:GND") (at 77.47 207.01 0) (unit 1)
    (in_bom yes) (on_board yes) (dnp no)
    (property "Reference" "#PWR0130" (at 77.47 213.36 0)
      (effects (font (size 1.27 1.27)) hide)
    )
    (property "Value" "GND" (at 77.47 210.82 0)
      (effects (font (size 1.27 1.27) (thickness 0.15)))
    )
    (property "Footprint" "" (at 86.36 214.63 0)
      (effects (font (size 1.27 1.27) (thickness 0.15)) (justify left bottom) hide)
    )
    (property "Datasheet" "" (at 86.36 219.71 0)
      (effects (font (size 1.27 1.27) (thickness 0.15)) (justify left bottom) hide)
    )
    (property "Author" "Antmicro" (at 86.36 214.63 0)
      (effects (font (size 1.27 1.27) (thickness 0.15)) (justify left bottom) hide)
    )
    (property "License" "Apache-2.0" (at 86.36 217.17 0)
      (effects (font (size 1.27 1.27) (thickness 0.15)) (justify left bottom) hide)
    )
    (pin "1")
    (instances
      (project "d1600e-psu-breakout-board"
        (path ""
          (reference "#PWR0130") (unit 1)
        )
      )
    )
  )

  (symbol (lib_id "antmicroResistors0603:R_4k7_0603") (at 203.2 250.19 90) (unit 1)
    (in_bom yes) (on_board yes) (dnp no)
    (property "Reference" "R53" (at 204.47 246.38 90)
      (effects (font (size 1.27 1.27)) (justify right))
    )
    (property "Value" "R_4k7_0603" (at 215.9 229.87 0)
      (effects (font (size 1.27 1.27) (thickness 0.15)) (justify left bottom) hide)
    )
    (property "Footprint" "antmicro-footprints:R_0603_1608Metric" (at 218.44 229.87 0)
      (effects (font (size 1.27 1.27) (thickness 0.15)) (justify left bottom) hide)
    )
    (property "Datasheet" "https://www.bourns.com/docs/product-datasheets/cr.pdf" (at 220.98 229.87 0)
      (effects (font (size 1.27 1.27) (thickness 0.15)) (justify left bottom) hide)
    )
    (property "Manufacturer" "Bourns" (at 226.06 229.87 0)
      (effects (font (size 1.27 1.27) (thickness 0.15)) (justify left bottom) hide)
    )
    (property "MPN" "CR0603-FX-4701ELF" (at 223.52 229.87 0)
      (effects (font (size 1.27 1.27) (thickness 0.15)) (justify left bottom) hide)
    )
    (property "Val" "4k7" (at 204.47 248.92 90)
      (effects (font (size 1.27 1.27) (thickness 0.15)) (justify right))
    )
    (property "License" "Apache-2.0" (at 228.6 229.87 0)
      (effects (font (size 1.27 1.27) (thickness 0.15)) (justify left bottom) hide)
    )
    (property "Author" "Antmicro" (at 231.14 229.87 0)
      (effects (font (size 1.27 1.27) (thickness 0.15)) (justify left bottom) hide)
    )
    (property "Tolerance" "1%" (at 213.36 229.87 0)
      (effects (font (size 1.27 1.27)) (justify left bottom) hide)
    )
    (pin "1")
    (pin "2")
    (instances
      (project "d1600e-psu-breakout-board"
        (path ""
          (reference "R53") (unit 1)
        )
      )
    )
  )

  (symbol (lib_id "antmicroWire2BoardConnectors:Molex_KK_1x4_22-27-2041") (at 93.98 237.49 0) (mirror x) (unit 1)
    (in_bom yes) (on_board yes) (dnp no)
    (property "Reference" "J14" (at 100.33 234.95 0)
      (effects (font (size 1.27 1.27) (thickness 0.15)) (justify left))
    )
    (property "Value" "Molex_KK_1x4_22-27-2041" (at 107.315 232.41 0)
      (effects (font (size 1.27 1.27) (thickness 0.15)) (justify left bottom) hide)
    )
    (property "Footprint" "antmicro-footprints:Conn_Molex_KK_1x4_22-27-2041" (at 107.315 229.87 0)
      (effects (font (size 1.27 1.27) (thickness 0.15)) (justify left bottom) hide)
    )
    (property "Datasheet" "https://www.molex.com/en-us/products/part-detail/22272041?display=pdf" (at 107.315 227.33 0)
      (effects (font (size 1.27 1.27) (thickness 0.15)) (justify left bottom) hide)
    )
    (property "MPN" "22-27-2041" (at 100.33 232.41 0)
      (effects (font (size 1.27 1.27) (thickness 0.15)) (justify left))
    )
    (property "Manufacturer" "Molex" (at 107.315 222.25 0)
      (effects (font (size 1.27 1.27) (thickness 0.15)) (justify left bottom) hide)
    )
    (property "Author" "Antmicro" (at 107.315 219.71 0)
      (effects (font (size 1.27 1.27) (thickness 0.15)) (justify left bottom) hide)
    )
    (property "License" "Apache-2.0" (at 107.315 217.17 0)
      (effects (font (size 1.27 1.27) (thickness 0.15)) (justify left bottom) hide)
    )
    (pin "3")
    (pin "1")
    (pin "2")
    (pin "4")
    (instances
      (project "d1600e-psu-breakout-board"
        (path ""
          (reference "J14") (unit 1)
        )
      )
    )
  )

  (symbol (lib_name "R_0R_0402_3") (lib_id "antmicroResistors0402:R_0R_0402") (at 93.98 64.77 0) (unit 1)
    (in_bom yes) (on_board yes) (dnp no)
    (property "Reference" "R72" (at 101.6 63.5 0)
      (effects (font (size 1.27 1.27) (thickness 0.15)))
    )
    (property "Value" "R_0R_0402" (at 114.3 77.47 0)
      (effects (font (size 1.27 1.27) (thickness 0.15)) (justify left bottom) hide)
    )
    (property "Footprint" "antmicro-footprints:R_0402_1005Metric" (at 114.3 80.01 0)
      (effects (font (size 1.27 1.27) (thickness 0.15)) (justify left bottom) hide)
    )
    (property "Datasheet" "https://industrial.panasonic.com/cdbs/www-data/pdf/RDA0000/AOA0000C301.pdf" (at 114.3 82.55 0)
      (effects (font (size 1.27 1.27) (thickness 0.15)) (justify left bottom) hide)
    )
    (property "MPN" "ERJ2GE0R00X" (at 114.3 85.09 0)
      (effects (font (size 1.27 1.27) (thickness 0.15)) (justify left bottom) hide)
    )
    (property "Manufacturer" "Panasonic" (at 114.3 87.63 0)
      (effects (font (size 1.27 1.27) (thickness 0.15)) (justify left bottom) hide)
    )
    (property "License" "Apache-2.0" (at 114.3 90.17 0)
      (effects (font (size 1.27 1.27) (thickness 0.15)) (justify left bottom) hide)
    )
    (property "Author" "Antmicro" (at 114.3 92.71 0)
      (effects (font (size 1.27 1.27) (thickness 0.15)) (justify left bottom) hide)
    )
    (property "Val" "0R" (at 92.71 63.5 0)
      (effects (font (size 1.27 1.27) (thickness 0.15)))
    )
    (property "Tolerance" "~" (at 114.3 74.93 0)
      (effects (font (size 1.27 1.27)) (justify left bottom) hide)
    )
    (property "Current" "1A" (at 114.3 95.25 0)
      (effects (font (size 1.27 1.27) (thickness 0.15)) (justify left bottom) hide)
    )
    (pin "1")
    (pin "2")
    (instances
      (project "d1600e-psu-breakout-board"
        (path ""
          (reference "R72") (unit 1)
        )
      )
    )
  )

  (symbol (lib_id "antmicropower:GND") (at 215.9 260.35 0) (unit 1)
    (in_bom yes) (on_board yes) (dnp no)
    (property "Reference" "#PWR0124" (at 215.9 266.7 0)
      (effects (font (size 1.27 1.27)) hide)
    )
    (property "Value" "GND" (at 215.9 264.16 0)
      (effects (font (size 1.27 1.27) (thickness 0.15)))
    )
    (property "Footprint" "" (at 224.79 267.97 0)
      (effects (font (size 1.27 1.27) (thickness 0.15)) (justify left bottom) hide)
    )
    (property "Datasheet" "" (at 224.79 273.05 0)
      (effects (font (size 1.27 1.27) (thickness 0.15)) (justify left bottom) hide)
    )
    (property "Author" "Antmicro" (at 224.79 267.97 0)
      (effects (font (size 1.27 1.27) (thickness 0.15)) (justify left bottom) hide)
    )
    (property "License" "Apache-2.0" (at 224.79 270.51 0)
      (effects (font (size 1.27 1.27) (thickness 0.15)) (justify left bottom) hide)
    )
    (pin "1")
    (instances
      (project "d1600e-psu-breakout-board"
        (path ""
          (reference "#PWR0124") (unit 1)
        )
      )
    )
  )

  (symbol (lib_name "LED_G_0603_LG_L29K-G2J1-24-Z_2") (lib_id "antmicroLEDIndicationDiscrete:LED_G_0603_LG_L29K-G2J1-24-Z") (at 177.8 257.81 90) (unit 1)
    (in_bom yes) (on_board yes) (dnp no)
    (property "Reference" "D6" (at 179.07 254 90)
      (effects (font (size 1.27 1.27)) (justify right))
    )
    (property "Value" "LED_G_0603_LG_L29K-G2J1-24-Z" (at 185.42 237.49 0)
      (effects (font (size 1.27 1.27) (thickness 0.15)) (justify left bottom) hide)
    )
    (property "Footprint" "antmicro-footprints:LED_0603_1608Metric_G" (at 187.96 237.49 0)
      (effects (font (size 1.27 1.27) (thickness 0.15)) (justify left bottom) hide)
    )
    (property "Datasheet" "https://look.ams-osram.com/m/19ee86b3ae0ee95b/original/LG-L29K.pdf" (at 190.5 237.49 0)
      (effects (font (size 1.27 1.27) (thickness 0.15)) (justify left bottom) hide)
    )
    (property "MPN" "LG L29K-G2J1-24-Z" (at 193.04 237.49 0)
      (effects (font (size 1.27 1.27) (thickness 0.15)) (justify left bottom) hide)
    )
    (property "Manufacturer" "OSRAM" (at 195.58 237.49 0)
      (effects (font (size 1.27 1.27) (thickness 0.15)) (justify left bottom) hide)
    )
    (property "Color" "Green" (at 179.07 256.54 90)
      (effects (font (size 1.27 1.27)) (justify right))
    )
    (property "Author" "Antmicro" (at 198.12 237.49 0)
      (effects (font (size 1.27 1.27) (thickness 0.15)) (justify left bottom) hide)
    )
    (property "License" "Apache-2.0" (at 200.66 237.49 0)
      (effects (font (size 1.27 1.27) (thickness 0.15)) (justify left bottom) hide)
    )
    (pin "1")
    (pin "2")
    (instances
      (project "d1600e-psu-breakout-board"
        (path ""
          (reference "D6") (unit 1)
        )
      )
    )
  )

  (symbol (lib_id "antmicropower:GND") (at 190.5 260.35 0) (unit 1)
    (in_bom yes) (on_board yes) (dnp no)
    (property "Reference" "#PWR09" (at 190.5 266.7 0)
      (effects (font (size 1.27 1.27)) hide)
    )
    (property "Value" "GND" (at 190.5 264.16 0)
      (effects (font (size 1.27 1.27) (thickness 0.15)))
    )
    (property "Footprint" "" (at 199.39 267.97 0)
      (effects (font (size 1.27 1.27) (thickness 0.15)) (justify left bottom) hide)
    )
    (property "Datasheet" "" (at 199.39 273.05 0)
      (effects (font (size 1.27 1.27) (thickness 0.15)) (justify left bottom) hide)
    )
    (property "Author" "Antmicro" (at 199.39 267.97 0)
      (effects (font (size 1.27 1.27) (thickness 0.15)) (justify left bottom) hide)
    )
    (property "License" "Apache-2.0" (at 199.39 270.51 0)
      (effects (font (size 1.27 1.27) (thickness 0.15)) (justify left bottom) hide)
    )
    (pin "1")
    (instances
      (project "d1600e-psu-breakout-board"
        (path ""
          (reference "#PWR09") (unit 1)
        )
      )
    )
  )

  (symbol (lib_id "antmicroWire2BoardConnectors:Molex_Mini-Fit-Jr_2x4_39-28-8080") (at 83.82 154.94 0) (unit 1)
    (in_bom yes) (on_board yes) (dnp no) (fields_autoplaced)
    (property "Reference" "J8" (at 90.17 148.59 0)
      (effects (font (size 1.27 1.27) (thickness 0.15)))
    )
    (property "Value" "Molex_Mini-Fit-Jr_2x4_39-28-8080" (at 110.49 163.83 0)
      (effects (font (size 1.27 1.27) (thickness 0.15)) (justify left bottom) hide)
    )
    (property "Footprint" "antmicro-footprints:MOLEX_39288080" (at 110.49 166.37 0)
      (effects (font (size 1.27 1.27) (thickness 0.15)) (justify left bottom) hide)
    )
    (property "Datasheet" "https://www.molex.com/pdm_docs/sd/039288080_sd.pdf" (at 110.49 168.91 0)
      (effects (font (size 1.27 1.27) (thickness 0.15)) (justify left bottom) hide)
    )
    (property "MPN" "39-28-8080" (at 90.17 151.13 0)
      (effects (font (size 1.27 1.27) (thickness 0.15)))
    )
    (property "Manufacturer" "Molex" (at 110.49 171.45 0)
      (effects (font (size 1.27 1.27) (thickness 0.15)) (justify left bottom) hide)
    )
    (property "Author" "Antmicro" (at 110.49 173.99 0)
      (effects (font (size 1.27 1.27) (thickness 0.15)) (justify left bottom) hide)
    )
    (property "License" "Apache-2.0" (at 110.49 176.53 0)
      (effects (font (size 1.27 1.27) (thickness 0.15)) (justify left bottom) hide)
    )
    (pin "3")
    (pin "8")
    (pin "6")
    (pin "5")
    (pin "4")
    (pin "2")
    (pin "7")
    (pin "1")
    (instances
      (project "d1600e-psu-breakout-board"
        (path ""
          (reference "J8") (unit 1)
        )
      )
    )
  )

  (symbol (lib_name "LED_G_0603_LG_L29K-G2J1-24-Z_1") (lib_id "antmicroLEDIndicationDiscrete:LED_G_0603_LG_L29K-G2J1-24-Z") (at 152.4 257.81 90) (unit 1)
    (in_bom yes) (on_board yes) (dnp no)
    (property "Reference" "D3" (at 153.67 254 90)
      (effects (font (size 1.27 1.27)) (justify right))
    )
    (property "Value" "LED_G_0603_LG_L29K-G2J1-24-Z" (at 160.02 237.49 0)
      (effects (font (size 1.27 1.27) (thickness 0.15)) (justify left bottom) hide)
    )
    (property "Footprint" "antmicro-footprints:LED_0603_1608Metric_G" (at 162.56 237.49 0)
      (effects (font (size 1.27 1.27) (thickness 0.15)) (justify left bottom) hide)
    )
    (property "Datasheet" "https://look.ams-osram.com/m/19ee86b3ae0ee95b/original/LG-L29K.pdf" (at 165.1 237.49 0)
      (effects (font (size 1.27 1.27) (thickness 0.15)) (justify left bottom) hide)
    )
    (property "MPN" "LG L29K-G2J1-24-Z" (at 167.64 237.49 0)
      (effects (font (size 1.27 1.27) (thickness 0.15)) (justify left bottom) hide)
    )
    (property "Manufacturer" "OSRAM" (at 170.18 237.49 0)
      (effects (font (size 1.27 1.27) (thickness 0.15)) (justify left bottom) hide)
    )
    (property "Color" "Green" (at 153.67 256.54 90)
      (effects (font (size 1.27 1.27)) (justify right))
    )
    (property "Author" "Antmicro" (at 172.72 237.49 0)
      (effects (font (size 1.27 1.27) (thickness 0.15)) (justify left bottom) hide)
    )
    (property "License" "Apache-2.0" (at 175.26 237.49 0)
      (effects (font (size 1.27 1.27) (thickness 0.15)) (justify left bottom) hide)
    )
    (pin "1")
    (pin "2")
    (instances
      (project "d1600e-psu-breakout-board"
        (path ""
          (reference "D3") (unit 1)
        )
      )
    )
  )

  (symbol (lib_id "antmicroWire2BoardConnectors:Molex_Mini-Fit-Jr_2x4_39-28-8080") (at 83.82 132.08 0) (unit 1)
    (in_bom yes) (on_board yes) (dnp no) (fields_autoplaced)
    (property "Reference" "J7" (at 90.17 125.73 0)
      (effects (font (size 1.27 1.27) (thickness 0.15)))
    )
    (property "Value" "Molex_Mini-Fit-Jr_2x4_39-28-8080" (at 110.49 140.97 0)
      (effects (font (size 1.27 1.27) (thickness 0.15)) (justify left bottom) hide)
    )
    (property "Footprint" "antmicro-footprints:MOLEX_39288080" (at 110.49 143.51 0)
      (effects (font (size 1.27 1.27) (thickness 0.15)) (justify left bottom) hide)
    )
    (property "Datasheet" "https://www.molex.com/pdm_docs/sd/039288080_sd.pdf" (at 110.49 146.05 0)
      (effects (font (size 1.27 1.27) (thickness 0.15)) (justify left bottom) hide)
    )
    (property "MPN" "39-28-8080" (at 90.17 128.27 0)
      (effects (font (size 1.27 1.27) (thickness 0.15)))
    )
    (property "Manufacturer" "Molex" (at 110.49 148.59 0)
      (effects (font (size 1.27 1.27) (thickness 0.15)) (justify left bottom) hide)
    )
    (property "Author" "Antmicro" (at 110.49 151.13 0)
      (effects (font (size 1.27 1.27) (thickness 0.15)) (justify left bottom) hide)
    )
    (property "License" "Apache-2.0" (at 110.49 153.67 0)
      (effects (font (size 1.27 1.27) (thickness 0.15)) (justify left bottom) hide)
    )
    (pin "3")
    (pin "8")
    (pin "6")
    (pin "5")
    (pin "4")
    (pin "2")
    (pin "7")
    (pin "1")
    (instances
      (project "d1600e-psu-breakout-board"
        (path ""
          (reference "J7") (unit 1)
        )
      )
    )
  )

  (symbol (lib_id "antmicroResistors0603:R_4k7_0603") (at 152.4 250.19 90) (unit 1)
    (in_bom yes) (on_board yes) (dnp no)
    (property "Reference" "R11" (at 153.67 246.38 90)
      (effects (font (size 1.27 1.27)) (justify right))
    )
    (property "Value" "R_4k7_0603" (at 165.1 229.87 0)
      (effects (font (size 1.27 1.27) (thickness 0.15)) (justify left bottom) hide)
    )
    (property "Footprint" "antmicro-footprints:R_0603_1608Metric" (at 167.64 229.87 0)
      (effects (font (size 1.27 1.27) (thickness 0.15)) (justify left bottom) hide)
    )
    (property "Datasheet" "https://www.bourns.com/docs/product-datasheets/cr.pdf" (at 170.18 229.87 0)
      (effects (font (size 1.27 1.27) (thickness 0.15)) (justify left bottom) hide)
    )
    (property "Manufacturer" "Bourns" (at 175.26 229.87 0)
      (effects (font (size 1.27 1.27) (thickness 0.15)) (justify left bottom) hide)
    )
    (property "MPN" "CR0603-FX-4701ELF" (at 172.72 229.87 0)
      (effects (font (size 1.27 1.27) (thickness 0.15)) (justify left bottom) hide)
    )
    (property "Val" "4k7" (at 153.67 248.92 90)
      (effects (font (size 1.27 1.27) (thickness 0.15)) (justify right))
    )
    (property "License" "Apache-2.0" (at 177.8 229.87 0)
      (effects (font (size 1.27 1.27) (thickness 0.15)) (justify left bottom) hide)
    )
    (property "Author" "Antmicro" (at 180.34 229.87 0)
      (effects (font (size 1.27 1.27) (thickness 0.15)) (justify left bottom) hide)
    )
    (property "Tolerance" "1%" (at 162.56 229.87 0)
      (effects (font (size 1.27 1.27)) (justify left bottom) hide)
    )
    (pin "1")
    (pin "2")
    (instances
      (project "d1600e-psu-breakout-board"
        (path ""
          (reference "R11") (unit 1)
        )
      )
    )
  )

  (symbol (lib_id "antmicroTransistorsBipolarSingle:BC856,215") (at 215.9 67.31 0) (mirror x) (unit 1)
    (in_bom yes) (on_board yes) (dnp no) (fields_autoplaced)
    (property "Reference" "Q11" (at 226.06 66.04 0)
      (effects (font (size 1.27 1.27) (thickness 0.15)) (justify left))
    )
    (property "Value" "BC856,215" (at 232.918 67.564 0)
      (effects (font (size 1.27 1.27) (thickness 0.15)) (justify left bottom) hide)
    )
    (property "Footprint" "antmicro-footprints:SOT-23-3" (at 232.918 65.024 0)
      (effects (font (size 1.27 1.27) (thickness 0.15)) (justify left bottom) hide)
    )
    (property "Datasheet" "https://eu.mouser.com/datasheet/2/916/BC856_BC857_BC858-1318701.pdf" (at 232.918 62.484 0)
      (effects (font (size 1.27 1.27) (thickness 0.15)) (justify left bottom) hide)
    )
    (property "MPN" "BC856,215" (at 226.06 68.58 0)
      (effects (font (size 1.27 1.27) (thickness 0.15)) (justify left))
    )
    (property "Manufacturer" "Nexperia" (at 232.918 57.404 0)
      (effects (font (size 1.27 1.27) (thickness 0.15)) (justify left bottom) hide)
    )
    (property "Author" "Antmicro" (at 232.918 54.864 0)
      (effects (font (size 1.27 1.27) (thickness 0.15)) (justify left bottom) hide)
    )
    (property "License" "Apache-2.0" (at 232.918 52.324 0)
      (effects (font (size 1.27 1.27) (thickness 0.15)) (justify left bottom) hide)
    )
    (pin "3")
    (pin "1")
    (pin "2")
    (instances
      (project "d1600e-psu-breakout-board"
        (path ""
          (reference "Q11") (unit 1)
        )
      )
    )
  )

  (symbol (lib_id "antmicroMechanicalParts:MP_Pad6mm_Drill3.2mm") (at 335.28 209.55 0) (unit 1)
    (in_bom no) (on_board yes) (dnp no) (fields_autoplaced)
    (property "Reference" "MP2" (at 344.17 208.28 0)
      (effects (font (size 1.27 1.27) (thickness 0.15)) (justify left))
    )
    (property "Value" "MP_Pad6mm_Drill3.2mm" (at 344.17 210.82 0)
      (effects (font (size 1.27 1.27) (thickness 0.15)) (justify left))
    )
    (property "Footprint" "antmicro-footprints:MP_Pad6mm_Drill3.2mm" (at 355.6 217.17 0)
      (effects (font (size 1.27 1.27) (thickness 0.15)) (justify left bottom) hide)
    )
    (property "Datasheet" "" (at 352.12 225.12 0)
      (effects (font (size 1.27 1.27) (thickness 0.15)) (justify left bottom) hide)
    )
    (property "Author" "Antmicro" (at 355.6 219.71 0)
      (effects (font (size 1.27 1.27) (thickness 0.15)) (justify left bottom) hide)
    )
    (property "License" "Apache-2.0" (at 355.6 222.25 0)
      (effects (font (size 1.27 1.27) (thickness 0.15)) (justify left bottom) hide)
    )
    (pin "1")
    (instances
      (project "d1600e-psu-breakout-board"
        (path ""
          (reference "MP2") (unit 1)
        )
      )
    )
  )

  (symbol (lib_id "antmicroResistors0603:R_4k7_0603") (at 177.8 250.19 90) (unit 1)
    (in_bom yes) (on_board yes) (dnp no)
    (property "Reference" "R51" (at 179.07 246.38 90)
      (effects (font (size 1.27 1.27)) (justify right))
    )
    (property "Value" "R_4k7_0603" (at 190.5 229.87 0)
      (effects (font (size 1.27 1.27) (thickness 0.15)) (justify left bottom) hide)
    )
    (property "Footprint" "antmicro-footprints:R_0603_1608Metric" (at 193.04 229.87 0)
      (effects (font (size 1.27 1.27) (thickness 0.15)) (justify left bottom) hide)
    )
    (property "Datasheet" "https://www.bourns.com/docs/product-datasheets/cr.pdf" (at 195.58 229.87 0)
      (effects (font (size 1.27 1.27) (thickness 0.15)) (justify left bottom) hide)
    )
    (property "Manufacturer" "Bourns" (at 200.66 229.87 0)
      (effects (font (size 1.27 1.27) (thickness 0.15)) (justify left bottom) hide)
    )
    (property "MPN" "CR0603-FX-4701ELF" (at 198.12 229.87 0)
      (effects (font (size 1.27 1.27) (thickness 0.15)) (justify left bottom) hide)
    )
    (property "Val" "4k7" (at 179.07 248.92 90)
      (effects (font (size 1.27 1.27) (thickness 0.15)) (justify right))
    )
    (property "License" "Apache-2.0" (at 203.2 229.87 0)
      (effects (font (size 1.27 1.27) (thickness 0.15)) (justify left bottom) hide)
    )
    (property "Author" "Antmicro" (at 205.74 229.87 0)
      (effects (font (size 1.27 1.27) (thickness 0.15)) (justify left bottom) hide)
    )
    (property "Tolerance" "1%" (at 187.96 229.87 0)
      (effects (font (size 1.27 1.27)) (justify left bottom) hide)
    )
    (pin "1")
    (pin "2")
    (instances
      (project "d1600e-psu-breakout-board"
        (path ""
          (reference "R51") (unit 1)
        )
      )
    )
  )

  (symbol (lib_id "antmicroMechanicalParts:MP_Pad6mm_Drill3.2mm") (at 335.28 203.2 0) (unit 1)
    (in_bom no) (on_board yes) (dnp no) (fields_autoplaced)
    (property "Reference" "MP1" (at 344.17 201.93 0)
      (effects (font (size 1.27 1.27) (thickness 0.15)) (justify left))
    )
    (property "Value" "MP_Pad6mm_Drill3.2mm" (at 344.17 204.47 0)
      (effects (font (size 1.27 1.27) (thickness 0.15)) (justify left))
    )
    (property "Footprint" "antmicro-footprints:MP_Pad6mm_Drill3.2mm" (at 355.6 210.82 0)
      (effects (font (size 1.27 1.27) (thickness 0.15)) (justify left bottom) hide)
    )
    (property "Datasheet" "" (at 352.12 218.77 0)
      (effects (font (size 1.27 1.27) (thickness 0.15)) (justify left bottom) hide)
    )
    (property "Author" "Antmicro" (at 355.6 213.36 0)
      (effects (font (size 1.27 1.27) (thickness 0.15)) (justify left bottom) hide)
    )
    (property "License" "Apache-2.0" (at 355.6 215.9 0)
      (effects (font (size 1.27 1.27) (thickness 0.15)) (justify left bottom) hide)
    )
    (pin "1")
    (instances
      (project "d1600e-psu-breakout-board"
        (path ""
          (reference "MP1") (unit 1)
        )
      )
    )
  )

  (symbol (lib_id "antmicroWire2BoardConnectors:Molex_Mini-Fit-Jr_2x4_39-28-8080") (at 48.26 153.67 0) (unit 1)
    (in_bom yes) (on_board yes) (dnp no) (fields_autoplaced)
    (property "Reference" "J5" (at 54.61 147.32 0)
      (effects (font (size 1.27 1.27) (thickness 0.15)))
    )
    (property "Value" "Molex_Mini-Fit-Jr_2x4_39-28-8080" (at 74.93 162.56 0)
      (effects (font (size 1.27 1.27) (thickness 0.15)) (justify left bottom) hide)
    )
    (property "Footprint" "antmicro-footprints:MOLEX_39288080" (at 74.93 165.1 0)
      (effects (font (size 1.27 1.27) (thickness 0.15)) (justify left bottom) hide)
    )
    (property "Datasheet" "https://www.molex.com/pdm_docs/sd/039288080_sd.pdf" (at 74.93 167.64 0)
      (effects (font (size 1.27 1.27) (thickness 0.15)) (justify left bottom) hide)
    )
    (property "MPN" "39-28-8080" (at 54.61 149.86 0)
      (effects (font (size 1.27 1.27) (thickness 0.15)))
    )
    (property "Manufacturer" "Molex" (at 74.93 170.18 0)
      (effects (font (size 1.27 1.27) (thickness 0.15)) (justify left bottom) hide)
    )
    (property "Author" "Antmicro" (at 74.93 172.72 0)
      (effects (font (size 1.27 1.27) (thickness 0.15)) (justify left bottom) hide)
    )
    (property "License" "Apache-2.0" (at 74.93 175.26 0)
      (effects (font (size 1.27 1.27) (thickness 0.15)) (justify left bottom) hide)
    )
    (pin "3")
    (pin "8")
    (pin "6")
    (pin "5")
    (pin "4")
    (pin "2")
    (pin "7")
    (pin "1")
    (instances
      (project "d1600e-psu-breakout-board"
        (path ""
          (reference "J5") (unit 1)
        )
      )
    )
  )

  (symbol (lib_id "antmicropower:GND") (at 152.4 260.35 0) (unit 1)
    (in_bom yes) (on_board yes) (dnp no)
    (property "Reference" "#PWR01" (at 152.4 266.7 0)
      (effects (font (size 1.27 1.27)) hide)
    )
    (property "Value" "GND" (at 152.4 264.16 0)
      (effects (font (size 1.27 1.27) (thickness 0.15)))
    )
    (property "Footprint" "" (at 161.29 267.97 0)
      (effects (font (size 1.27 1.27) (thickness 0.15)) (justify left bottom) hide)
    )
    (property "Datasheet" "" (at 161.29 273.05 0)
      (effects (font (size 1.27 1.27) (thickness 0.15)) (justify left bottom) hide)
    )
    (property "Author" "Antmicro" (at 161.29 267.97 0)
      (effects (font (size 1.27 1.27) (thickness 0.15)) (justify left bottom) hide)
    )
    (property "License" "Apache-2.0" (at 161.29 270.51 0)
      (effects (font (size 1.27 1.27) (thickness 0.15)) (justify left bottom) hide)
    )
    (pin "1")
    (instances
      (project "d1600e-psu-breakout-board"
        (path ""
          (reference "#PWR01") (unit 1)
        )
      )
    )
  )

  (symbol (lib_id "antmicropower:GND") (at 77.47 222.25 0) (unit 1)
    (in_bom yes) (on_board yes) (dnp no)
    (property "Reference" "#PWR0133" (at 77.47 228.6 0)
      (effects (font (size 1.27 1.27)) hide)
    )
    (property "Value" "GND" (at 77.47 226.06 0)
      (effects (font (size 1.27 1.27) (thickness 0.15)))
    )
    (property "Footprint" "" (at 86.36 229.87 0)
      (effects (font (size 1.27 1.27) (thickness 0.15)) (justify left bottom) hide)
    )
    (property "Datasheet" "" (at 86.36 234.95 0)
      (effects (font (size 1.27 1.27) (thickness 0.15)) (justify left bottom) hide)
    )
    (property "Author" "Antmicro" (at 86.36 229.87 0)
      (effects (font (size 1.27 1.27) (thickness 0.15)) (justify left bottom) hide)
    )
    (property "License" "Apache-2.0" (at 86.36 232.41 0)
      (effects (font (size 1.27 1.27) (thickness 0.15)) (justify left bottom) hide)
    )
    (pin "1")
    (instances
      (project "d1600e-psu-breakout-board"
        (path ""
          (reference "#PWR0133") (unit 1)
        )
      )
    )
  )

  (symbol (lib_id "antmicroMechanicalParts:MP_Pad6mm_Drill3.2mm") (at 335.28 222.25 0) (unit 1)
    (in_bom no) (on_board yes) (dnp no) (fields_autoplaced)
    (property "Reference" "MP4" (at 344.17 220.98 0)
      (effects (font (size 1.27 1.27) (thickness 0.15)) (justify left))
    )
    (property "Value" "MP_Pad6mm_Drill3.2mm" (at 344.17 223.52 0)
      (effects (font (size 1.27 1.27) (thickness 0.15)) (justify left))
    )
    (property "Footprint" "antmicro-footprints:MP_Pad6mm_Drill3.2mm" (at 355.6 229.87 0)
      (effects (font (size 1.27 1.27) (thickness 0.15)) (justify left bottom) hide)
    )
    (property "Datasheet" "" (at 352.12 237.82 0)
      (effects (font (size 1.27 1.27) (thickness 0.15)) (justify left bottom) hide)
    )
    (property "Author" "Antmicro" (at 355.6 232.41 0)
      (effects (font (size 1.27 1.27) (thickness 0.15)) (justify left bottom) hide)
    )
    (property "License" "Apache-2.0" (at 355.6 234.95 0)
      (effects (font (size 1.27 1.27) (thickness 0.15)) (justify left bottom) hide)
    )
    (pin "1")
    (instances
      (project "d1600e-psu-breakout-board"
        (path ""
          (reference "MP4") (unit 1)
        )
      )
    )
  )

  (symbol (lib_id "antmicropower:GND") (at 203.2 260.35 0) (unit 1)
    (in_bom yes) (on_board yes) (dnp no)
    (property "Reference" "#PWR0121" (at 203.2 266.7 0)
      (effects (font (size 1.27 1.27)) hide)
    )
    (property "Value" "GND" (at 203.2 264.16 0)
      (effects (font (size 1.27 1.27) (thickness 0.15)))
    )
    (property "Footprint" "" (at 212.09 267.97 0)
      (effects (font (size 1.27 1.27) (thickness 0.15)) (justify left bottom) hide)
    )
    (property "Datasheet" "" (at 212.09 273.05 0)
      (effects (font (size 1.27 1.27) (thickness 0.15)) (justify left bottom) hide)
    )
    (property "Author" "Antmicro" (at 212.09 267.97 0)
      (effects (font (size 1.27 1.27) (thickness 0.15)) (justify left bottom) hide)
    )
    (property "License" "Apache-2.0" (at 212.09 270.51 0)
      (effects (font (size 1.27 1.27) (thickness 0.15)) (justify left bottom) hide)
    )
    (pin "1")
    (instances
      (project "d1600e-psu-breakout-board"
        (path ""
          (reference "#PWR0121") (unit 1)
        )
      )
    )
  )

  (symbol (lib_name "LED_G_0603_LG_L29K-G2J1-24-Z_3") (lib_id "antmicroLEDIndicationDiscrete:LED_G_0603_LG_L29K-G2J1-24-Z") (at 165.1 257.81 90) (unit 1)
    (in_bom yes) (on_board yes) (dnp no)
    (property "Reference" "D4" (at 166.37 254 90)
      (effects (font (size 1.27 1.27)) (justify right))
    )
    (property "Value" "LED_G_0603_LG_L29K-G2J1-24-Z" (at 172.72 237.49 0)
      (effects (font (size 1.27 1.27) (thickness 0.15)) (justify left bottom) hide)
    )
    (property "Footprint" "antmicro-footprints:LED_0603_1608Metric_G" (at 175.26 237.49 0)
      (effects (font (size 1.27 1.27) (thickness 0.15)) (justify left bottom) hide)
    )
    (property "Datasheet" "https://look.ams-osram.com/m/19ee86b3ae0ee95b/original/LG-L29K.pdf" (at 177.8 237.49 0)
      (effects (font (size 1.27 1.27) (thickness 0.15)) (justify left bottom) hide)
    )
    (property "MPN" "LG L29K-G2J1-24-Z" (at 180.34 237.49 0)
      (effects (font (size 1.27 1.27) (thickness 0.15)) (justify left bottom) hide)
    )
    (property "Manufacturer" "OSRAM" (at 182.88 237.49 0)
      (effects (font (size 1.27 1.27) (thickness 0.15)) (justify left bottom) hide)
    )
    (property "Color" "Green" (at 166.37 256.54 90)
      (effects (font (size 1.27 1.27)) (justify right))
    )
    (property "Author" "Antmicro" (at 185.42 237.49 0)
      (effects (font (size 1.27 1.27) (thickness 0.15)) (justify left bottom) hide)
    )
    (property "License" "Apache-2.0" (at 187.96 237.49 0)
      (effects (font (size 1.27 1.27) (thickness 0.15)) (justify left bottom) hide)
    )
    (pin "1")
    (pin "2")
    (instances
      (project "d1600e-psu-breakout-board"
        (path ""
          (reference "D4") (unit 1)
        )
      )
    )
  )

  (symbol (lib_name "LED_G_0603_LG_L29K-G2J1-24-Z_4") (lib_id "antmicroLEDIndicationDiscrete:LED_G_0603_LG_L29K-G2J1-24-Z") (at 190.5 257.81 90) (unit 1)
    (in_bom yes) (on_board yes) (dnp no)
    (property "Reference" "D7" (at 191.77 254 90)
      (effects (font (size 1.27 1.27)) (justify right))
    )
    (property "Value" "LED_G_0603_LG_L29K-G2J1-24-Z" (at 198.12 237.49 0)
      (effects (font (size 1.27 1.27) (thickness 0.15)) (justify left bottom) hide)
    )
    (property "Footprint" "antmicro-footprints:LED_0603_1608Metric_G" (at 200.66 237.49 0)
      (effects (font (size 1.27 1.27) (thickness 0.15)) (justify left bottom) hide)
    )
    (property "Datasheet" "https://look.ams-osram.com/m/19ee86b3ae0ee95b/original/LG-L29K.pdf" (at 203.2 237.49 0)
      (effects (font (size 1.27 1.27) (thickness 0.15)) (justify left bottom) hide)
    )
    (property "MPN" "LG L29K-G2J1-24-Z" (at 205.74 237.49 0)
      (effects (font (size 1.27 1.27) (thickness 0.15)) (justify left bottom) hide)
    )
    (property "Manufacturer" "OSRAM" (at 208.28 237.49 0)
      (effects (font (size 1.27 1.27) (thickness 0.15)) (justify left bottom) hide)
    )
    (property "Color" "Green" (at 191.77 256.54 90)
      (effects (font (size 1.27 1.27)) (justify right))
    )
    (property "Author" "Antmicro" (at 210.82 237.49 0)
      (effects (font (size 1.27 1.27) (thickness 0.15)) (justify left bottom) hide)
    )
    (property "License" "Apache-2.0" (at 213.36 237.49 0)
      (effects (font (size 1.27 1.27) (thickness 0.15)) (justify left bottom) hide)
    )
    (pin "1")
    (pin "2")
    (instances
      (project "d1600e-psu-breakout-board"
        (path ""
          (reference "D7") (unit 1)
        )
      )
    )
  )

  (symbol (lib_id "antmicroWire2BoardConnectors:Molex_Mini-Fit-Jr_2x4_39-28-8080") (at 48.26 130.81 0) (unit 1)
    (in_bom yes) (on_board yes) (dnp no) (fields_autoplaced)
    (property "Reference" "J4" (at 54.61 124.46 0)
      (effects (font (size 1.27 1.27) (thickness 0.15)))
    )
    (property "Value" "Molex_Mini-Fit-Jr_2x4_39-28-8080" (at 74.93 139.7 0)
      (effects (font (size 1.27 1.27) (thickness 0.15)) (justify left bottom) hide)
    )
    (property "Footprint" "antmicro-footprints:MOLEX_39288080" (at 74.93 142.24 0)
      (effects (font (size 1.27 1.27) (thickness 0.15)) (justify left bottom) hide)
    )
    (property "Datasheet" "https://www.molex.com/pdm_docs/sd/039288080_sd.pdf" (at 74.93 144.78 0)
      (effects (font (size 1.27 1.27) (thickness 0.15)) (justify left bottom) hide)
    )
    (property "MPN" "39-28-8080" (at 54.61 127 0)
      (effects (font (size 1.27 1.27) (thickness 0.15)))
    )
    (property "Manufacturer" "Molex" (at 74.93 147.32 0)
      (effects (font (size 1.27 1.27) (thickness 0.15)) (justify left bottom) hide)
    )
    (property "Author" "Antmicro" (at 74.93 149.86 0)
      (effects (font (size 1.27 1.27) (thickness 0.15)) (justify left bottom) hide)
    )
    (property "License" "Apache-2.0" (at 74.93 152.4 0)
      (effects (font (size 1.27 1.27) (thickness 0.15)) (justify left bottom) hide)
    )
    (pin "3")
    (pin "8")
    (pin "6")
    (pin "5")
    (pin "4")
    (pin "2")
    (pin "7")
    (pin "1")
    (instances
      (project "d1600e-psu-breakout-board"
        (path ""
          (reference "J4") (unit 1)
        )
      )
    )
  )

  (symbol (lib_id "antmicroWire2BoardConnectors:Molex_KK_1x4_22-27-2041") (at 46.99 224.79 0) (mirror x) (unit 1)
    (in_bom yes) (on_board yes) (dnp no)
    (property "Reference" "J11" (at 53.34 222.25 0)
      (effects (font (size 1.27 1.27) (thickness 0.15)) (justify left))
    )
    (property "Value" "Molex_KK_1x4_22-27-2041" (at 60.325 219.71 0)
      (effects (font (size 1.27 1.27) (thickness 0.15)) (justify left bottom) hide)
    )
    (property "Footprint" "antmicro-footprints:Conn_Molex_KK_1x4_22-27-2041" (at 60.325 217.17 0)
      (effects (font (size 1.27 1.27) (thickness 0.15)) (justify left bottom) hide)
    )
    (property "Datasheet" "https://www.molex.com/en-us/products/part-detail/22272041?display=pdf" (at 60.325 214.63 0)
      (effects (font (size 1.27 1.27) (thickness 0.15)) (justify left bottom) hide)
    )
    (property "MPN" "22-27-2041" (at 53.34 219.71 0)
      (effects (font (size 1.27 1.27) (thickness 0.15)) (justify left))
    )
    (property "Manufacturer" "Molex" (at 60.325 209.55 0)
      (effects (font (size 1.27 1.27) (thickness 0.15)) (justify left bottom) hide)
    )
    (property "Author" "Antmicro" (at 60.325 207.01 0)
      (effects (font (size 1.27 1.27) (thickness 0.15)) (justify left bottom) hide)
    )
    (property "License" "Apache-2.0" (at 60.325 204.47 0)
      (effects (font (size 1.27 1.27) (thickness 0.15)) (justify left bottom) hide)
    )
    (pin "3")
    (pin "1")
    (pin "2")
    (pin "4")
    (instances
      (project "d1600e-psu-breakout-board"
        (path ""
          (reference "J11") (unit 1)
        )
      )
    )
  )

  (symbol (lib_id "antmicroResistors0603:R_1k_0603") (at 227.33 250.19 90) (unit 1)
    (in_bom yes) (on_board yes) (dnp no)
    (property "Reference" "R55" (at 228.6 246.38 90)
      (effects (font (size 1.27 1.27)) (justify right))
    )
    (property "Value" "R_1k_0603" (at 240.03 229.87 0)
      (effects (font (size 1.27 1.27) (thickness 0.15)) (justify left bottom) hide)
    )
    (property "Footprint" "antmicro-footprints:R_0603_1608Metric" (at 242.57 229.87 0)
      (effects (font (size 1.27 1.27) (thickness 0.15)) (justify left bottom) hide)
    )
    (property "Datasheet" "https://www.bourns.com/docs/product-datasheets/cr.pdf" (at 245.11 229.87 0)
      (effects (font (size 1.27 1.27) (thickness 0.15)) (justify left bottom) hide)
    )
    (property "Manufacturer" "Bourns" (at 250.19 229.87 0)
      (effects (font (size 1.27 1.27) (thickness 0.15)) (justify left bottom) hide)
    )
    (property "MPN" "CR0603-FX-1001ELF" (at 247.65 229.87 0)
      (effects (font (size 1.27 1.27) (thickness 0.15)) (justify left bottom) hide)
    )
    (property "Val" "1k" (at 228.6 248.92 90)
      (effects (font (size 1.27 1.27) (thickness 0.15)) (justify right))
    )
    (property "License" "Apache-2.0" (at 252.73 229.87 0)
      (effects (font (size 1.27 1.27) (thickness 0.15)) (justify left bottom) hide)
    )
    (property "Author" "Antmicro" (at 255.27 229.87 0)
      (effects (font (size 1.27 1.27) (thickness 0.15)) (justify left bottom) hide)
    )
    (property "Tolerance" "1%" (at 237.49 229.87 0)
      (effects (font (size 1.27 1.27)) (justify left bottom) hide)
    )
    (pin "1")
    (pin "2")
    (instances
      (project "d1600e-psu-breakout-board"
        (path ""
          (reference "R55") (unit 1)
        )
      )
    )
  )

  (symbol (lib_id "antmicropower:GND") (at 227.33 260.35 0) (unit 1)
    (in_bom yes) (on_board yes) (dnp no)
    (property "Reference" "#PWR0123" (at 227.33 266.7 0)
      (effects (font (size 1.27 1.27)) hide)
    )
    (property "Value" "GND" (at 227.33 264.16 0)
      (effects (font (size 1.27 1.27) (thickness 0.15)))
    )
    (property "Footprint" "" (at 236.22 267.97 0)
      (effects (font (size 1.27 1.27) (thickness 0.15)) (justify left bottom) hide)
    )
    (property "Datasheet" "" (at 236.22 273.05 0)
      (effects (font (size 1.27 1.27) (thickness 0.15)) (justify left bottom) hide)
    )
    (property "Author" "Antmicro" (at 236.22 267.97 0)
      (effects (font (size 1.27 1.27) (thickness 0.15)) (justify left bottom) hide)
    )
    (property "License" "Apache-2.0" (at 236.22 270.51 0)
      (effects (font (size 1.27 1.27) (thickness 0.15)) (justify left bottom) hide)
    )
    (pin "1")
    (instances
      (project "d1600e-psu-breakout-board"
        (path ""
          (reference "#PWR0123") (unit 1)
        )
      )
    )
  )

  (symbol (lib_id "antmicroResistors0603:R_2k2_0603") (at 238.76 250.19 90) (unit 1)
    (in_bom yes) (on_board yes) (dnp no)
    (property "Reference" "R56" (at 240.03 246.38 90)
      (effects (font (size 1.27 1.27)) (justify right))
    )
    (property "Value" "R_2k2_0603" (at 251.46 229.87 0)
      (effects (font (size 1.27 1.27) (thickness 0.15)) (justify left bottom) hide)
    )
    (property "Footprint" "antmicro-footprints:R_0603_1608Metric" (at 254 229.87 0)
      (effects (font (size 1.27 1.27) (thickness 0.15)) (justify left bottom) hide)
    )
    (property "Datasheet" "https://www.bourns.com/docs/product-datasheets/cr.pdf" (at 256.54 229.87 0)
      (effects (font (size 1.27 1.27) (thickness 0.15)) (justify left bottom) hide)
    )
    (property "Manufacturer" "Bourns" (at 261.62 229.87 0)
      (effects (font (size 1.27 1.27) (thickness 0.15)) (justify left bottom) hide)
    )
    (property "MPN" "CR0603-FX-2201ELF" (at 259.08 229.87 0)
      (effects (font (size 1.27 1.27) (thickness 0.15)) (justify left bottom) hide)
    )
    (property "Val" "2k2" (at 240.03 248.92 90)
      (effects (font (size 1.27 1.27) (thickness 0.15)) (justify right))
    )
    (property "License" "Apache-2.0" (at 264.16 229.87 0)
      (effects (font (size 1.27 1.27) (thickness 0.15)) (justify left bottom) hide)
    )
    (property "Author" "Antmicro" (at 266.7 229.87 0)
      (effects (font (size 1.27 1.27) (thickness 0.15)) (justify left bottom) hide)
    )
    (property "Tolerance" "1%" (at 248.92 229.87 0)
      (effects (font (size 1.27 1.27)) (justify left bottom) hide)
    )
    (pin "1")
    (pin "2")
    (instances
      (project "d1600e-psu-breakout-board"
        (path ""
          (reference "R56") (unit 1)
        )
      )
    )
  )

  (symbol (lib_id "antmicroResistors0603:R_1k_0603") (at 215.9 250.19 90) (unit 1)
    (in_bom yes) (on_board yes) (dnp no)
    (property "Reference" "R54" (at 217.17 246.38 90)
      (effects (font (size 1.27 1.27)) (justify right))
    )
    (property "Value" "R_1k_0603" (at 228.6 229.87 0)
      (effects (font (size 1.27 1.27) (thickness 0.15)) (justify left bottom) hide)
    )
    (property "Footprint" "antmicro-footprints:R_0603_1608Metric" (at 231.14 229.87 0)
      (effects (font (size 1.27 1.27) (thickness 0.15)) (justify left bottom) hide)
    )
    (property "Datasheet" "https://www.bourns.com/docs/product-datasheets/cr.pdf" (at 233.68 229.87 0)
      (effects (font (size 1.27 1.27) (thickness 0.15)) (justify left bottom) hide)
    )
    (property "Manufacturer" "Bourns" (at 238.76 229.87 0)
      (effects (font (size 1.27 1.27) (thickness 0.15)) (justify left bottom) hide)
    )
    (property "MPN" "CR0603-FX-1001ELF" (at 236.22 229.87 0)
      (effects (font (size 1.27 1.27) (thickness 0.15)) (justify left bottom) hide)
    )
    (property "Val" "1k" (at 217.17 248.92 90)
      (effects (font (size 1.27 1.27) (thickness 0.15)) (justify right))
    )
    (property "License" "Apache-2.0" (at 241.3 229.87 0)
      (effects (font (size 1.27 1.27) (thickness 0.15)) (justify left bottom) hide)
    )
    (property "Author" "Antmicro" (at 243.84 229.87 0)
      (effects (font (size 1.27 1.27) (thickness 0.15)) (justify left bottom) hide)
    )
    (property "Tolerance" "1%" (at 226.06 229.87 0)
      (effects (font (size 1.27 1.27)) (justify left bottom) hide)
    )
    (pin "1")
    (pin "2")
    (instances
      (project "d1600e-psu-breakout-board"
        (path ""
          (reference "R54") (unit 1)
        )
      )
    )
  )

  (symbol (lib_name "R_0R_0402_2") (lib_id "antmicroResistors0402:R_0R_0402") (at 93.98 72.39 0) (unit 1)
    (in_bom no) (on_board yes) (dnp yes)
    (property "Reference" "R71" (at 101.6 71.12 0)
      (effects (font (size 1.27 1.27) (thickness 0.15)))
    )
    (property "Value" "R_0R_0402" (at 114.3 85.09 0)
      (effects (font (size 1.27 1.27) (thickness 0.15)) (justify left bottom) hide)
    )
    (property "Footprint" "antmicro-footprints:R_0402_1005Metric" (at 114.3 87.63 0)
      (effects (font (size 1.27 1.27) (thickness 0.15)) (justify left bottom) hide)
    )
    (property "Datasheet" "https://industrial.panasonic.com/cdbs/www-data/pdf/RDA0000/AOA0000C301.pdf" (at 114.3 90.17 0)
      (effects (font (size 1.27 1.27) (thickness 0.15)) (justify left bottom) hide)
    )
    (property "MPN" "ERJ2GE0R00X" (at 114.3 92.71 0)
      (effects (font (size 1.27 1.27) (thickness 0.15)) (justify left bottom) hide)
    )
    (property "Manufacturer" "Panasonic" (at 114.3 95.25 0)
      (effects (font (size 1.27 1.27) (thickness 0.15)) (justify left bottom) hide)
    )
    (property "License" "Apache-2.0" (at 114.3 97.79 0)
      (effects (font (size 1.27 1.27) (thickness 0.15)) (justify left bottom) hide)
    )
    (property "Author" "Antmicro" (at 114.3 100.33 0)
      (effects (font (size 1.27 1.27) (thickness 0.15)) (justify left bottom) hide)
    )
    (property "Val" "0R" (at 92.71 71.12 0)
      (effects (font (size 1.27 1.27) (thickness 0.15)))
    )
    (property "Tolerance" "~" (at 114.3 82.55 0)
      (effects (font (size 1.27 1.27)) (justify left bottom) hide)
    )
    (property "Current" "1A" (at 114.3 102.87 0)
      (effects (font (size 1.27 1.27) (thickness 0.15)) (justify left bottom) hide)
    )
    (property "DNP" "DNP" (at 96.52 69.85 0)
      (effects (font (size 1.27 1.27)))
    )
    (pin "1")
    (pin "2")
    (instances
      (project "d1600e-psu-breakout-board"
        (path ""
          (reference "R71") (unit 1)
        )
      )
    )
  )

  (symbol (lib_id "antmicropower:GND") (at 30.48 222.25 0) (unit 1)
    (in_bom yes) (on_board yes) (dnp no)
    (property "Reference" "#PWR0132" (at 30.48 228.6 0)
      (effects (font (size 1.27 1.27)) hide)
    )
    (property "Value" "GND" (at 30.48 226.06 0)
      (effects (font (size 1.27 1.27) (thickness 0.15)))
    )
    (property "Footprint" "" (at 39.37 229.87 0)
      (effects (font (size 1.27 1.27) (thickness 0.15)) (justify left bottom) hide)
    )
    (property "Datasheet" "" (at 39.37 234.95 0)
      (effects (font (size 1.27 1.27) (thickness 0.15)) (justify left bottom) hide)
    )
    (property "Author" "Antmicro" (at 39.37 229.87 0)
      (effects (font (size 1.27 1.27) (thickness 0.15)) (justify left bottom) hide)
    )
    (property "License" "Apache-2.0" (at 39.37 232.41 0)
      (effects (font (size 1.27 1.27) (thickness 0.15)) (justify left bottom) hide)
    )
    (pin "1")
    (instances
      (project "d1600e-psu-breakout-board"
        (path ""
          (reference "#PWR0132") (unit 1)
        )
      )
    )
  )

  (symbol (lib_name "LED_G_0603_LG_L29K-G2J1-24-Z_5") (lib_id "antmicroLEDIndicationDiscrete:LED_G_0603_LG_L29K-G2J1-24-Z") (at 238.76 257.81 90) (unit 1)
    (in_bom yes) (on_board yes) (dnp no)
    (property "Reference" "D11" (at 240.03 254 90)
      (effects (font (size 1.27 1.27)) (justify right))
    )
    (property "Value" "LED_G_0603_LG_L29K-G2J1-24-Z" (at 246.38 237.49 0)
      (effects (font (size 1.27 1.27) (thickness 0.15)) (justify left bottom) hide)
    )
    (property "Footprint" "antmicro-footprints:LED_0603_1608Metric_G" (at 248.92 237.49 0)
      (effects (font (size 1.27 1.27) (thickness 0.15)) (justify left bottom) hide)
    )
    (property "Datasheet" "https://look.ams-osram.com/m/19ee86b3ae0ee95b/original/LG-L29K.pdf" (at 251.46 237.49 0)
      (effects (font (size 1.27 1.27) (thickness 0.15)) (justify left bottom) hide)
    )
    (property "MPN" "LG L29K-G2J1-24-Z" (at 254 237.49 0)
      (effects (font (size 1.27 1.27) (thickness 0.15)) (justify left bottom) hide)
    )
    (property "Manufacturer" "OSRAM" (at 256.54 237.49 0)
      (effects (font (size 1.27 1.27) (thickness 0.15)) (justify left bottom) hide)
    )
    (property "Color" "Green" (at 240.03 256.54 90)
      (effects (font (size 1.27 1.27)) (justify right))
    )
    (property "Author" "Antmicro" (at 259.08 237.49 0)
      (effects (font (size 1.27 1.27) (thickness 0.15)) (justify left bottom) hide)
    )
    (property "License" "Apache-2.0" (at 261.62 237.49 0)
      (effects (font (size 1.27 1.27) (thickness 0.15)) (justify left bottom) hide)
    )
    (pin "1")
    (pin "2")
    (instances
      (project "d1600e-psu-breakout-board"
        (path ""
          (reference "D11") (unit 1)
        )
      )
    )
  )

  (symbol (lib_id "antmicropower:GND") (at 102.87 102.87 0) (unit 1)
    (in_bom yes) (on_board yes) (dnp no)
    (property "Reference" "#PWR0129" (at 102.87 109.22 0)
      (effects (font (size 1.27 1.27)) hide)
    )
    (property "Value" "GND" (at 102.87 106.68 0)
      (effects (font (size 1.27 1.27) (thickness 0.15)))
    )
    (property "Footprint" "" (at 111.76 110.49 0)
      (effects (font (size 1.27 1.27) (thickness 0.15)) (justify left bottom) hide)
    )
    (property "Datasheet" "" (at 111.76 115.57 0)
      (effects (font (size 1.27 1.27) (thickness 0.15)) (justify left bottom) hide)
    )
    (property "Author" "Antmicro" (at 111.76 110.49 0)
      (effects (font (size 1.27 1.27) (thickness 0.15)) (justify left bottom) hide)
    )
    (property "License" "Apache-2.0" (at 111.76 113.03 0)
      (effects (font (size 1.27 1.27) (thickness 0.15)) (justify left bottom) hide)
    )
    (pin "1")
    (instances
      (project "d1600e-psu-breakout-board"
        (path ""
          (reference "#PWR0129") (unit 1)
        )
      )
    )
  )

  (symbol (lib_id "antmicropower:GND") (at 165.1 260.35 0) (unit 1)
    (in_bom yes) (on_board yes) (dnp no)
    (property "Reference" "#PWR04" (at 165.1 266.7 0)
      (effects (font (size 1.27 1.27)) hide)
    )
    (property "Value" "GND" (at 165.1 264.16 0)
      (effects (font (size 1.27 1.27) (thickness 0.15)))
    )
    (property "Footprint" "" (at 173.99 267.97 0)
      (effects (font (size 1.27 1.27) (thickness 0.15)) (justify left bottom) hide)
    )
    (property "Datasheet" "" (at 173.99 273.05 0)
      (effects (font (size 1.27 1.27) (thickness 0.15)) (justify left bottom) hide)
    )
    (property "Author" "Antmicro" (at 173.99 267.97 0)
      (effects (font (size 1.27 1.27) (thickness 0.15)) (justify left bottom) hide)
    )
    (property "License" "Apache-2.0" (at 173.99 270.51 0)
      (effects (font (size 1.27 1.27) (thickness 0.15)) (justify left bottom) hide)
    )
    (pin "1")
    (instances
      (project "d1600e-psu-breakout-board"
        (path ""
          (reference "#PWR04") (unit 1)
        )
      )
    )
  )

  (symbol (lib_id "antmicropower:GND") (at 238.76 260.35 0) (unit 1)
    (in_bom yes) (on_board yes) (dnp no)
    (property "Reference" "#PWR0122" (at 238.76 266.7 0)
      (effects (font (size 1.27 1.27)) hide)
    )
    (property "Value" "GND" (at 238.76 264.16 0)
      (effects (font (size 1.27 1.27) (thickness 0.15)))
    )
    (property "Footprint" "" (at 247.65 267.97 0)
      (effects (font (size 1.27 1.27) (thickness 0.15)) (justify left bottom) hide)
    )
    (property "Datasheet" "" (at 247.65 273.05 0)
      (effects (font (size 1.27 1.27) (thickness 0.15)) (justify left bottom) hide)
    )
    (property "Author" "Antmicro" (at 247.65 267.97 0)
      (effects (font (size 1.27 1.27) (thickness 0.15)) (justify left bottom) hide)
    )
    (property "License" "Apache-2.0" (at 247.65 270.51 0)
      (effects (font (size 1.27 1.27) (thickness 0.15)) (justify left bottom) hide)
    )
    (pin "1")
    (instances
      (project "d1600e-psu-breakout-board"
        (path ""
          (reference "#PWR0122") (unit 1)
        )
      )
    )
  )

  (symbol (lib_id "antmicroResistors0603:R_4k7_0603") (at 190.5 250.19 90) (unit 1)
    (in_bom yes) (on_board yes) (dnp no)
    (property "Reference" "R52" (at 191.77 246.38 90)
      (effects (font (size 1.27 1.27)) (justify right))
    )
    (property "Value" "R_4k7_0603" (at 203.2 229.87 0)
      (effects (font (size 1.27 1.27) (thickness 0.15)) (justify left bottom) hide)
    )
    (property "Footprint" "antmicro-footprints:R_0603_1608Metric" (at 205.74 229.87 0)
      (effects (font (size 1.27 1.27) (thickness 0.15)) (justify left bottom) hide)
    )
    (property "Datasheet" "https://www.bourns.com/docs/product-datasheets/cr.pdf" (at 208.28 229.87 0)
      (effects (font (size 1.27 1.27) (thickness 0.15)) (justify left bottom) hide)
    )
    (property "Manufacturer" "Bourns" (at 213.36 229.87 0)
      (effects (font (size 1.27 1.27) (thickness 0.15)) (justify left bottom) hide)
    )
    (property "MPN" "CR0603-FX-4701ELF" (at 210.82 229.87 0)
      (effects (font (size 1.27 1.27) (thickness 0.15)) (justify left bottom) hide)
    )
    (property "Val" "4k7" (at 191.77 248.92 90)
      (effects (font (size 1.27 1.27) (thickness 0.15)) (justify right))
    )
    (property "License" "Apache-2.0" (at 215.9 229.87 0)
      (effects (font (size 1.27 1.27) (thickness 0.15)) (justify left bottom) hide)
    )
    (property "Author" "Antmicro" (at 218.44 229.87 0)
      (effects (font (size 1.27 1.27) (thickness 0.15)) (justify left bottom) hide)
    )
    (property "Tolerance" "1%" (at 200.66 229.87 0)
      (effects (font (size 1.27 1.27)) (justify left bottom) hide)
    )
    (pin "1")
    (pin "2")
    (instances
      (project "d1600e-psu-breakout-board"
        (path ""
          (reference "R52") (unit 1)
        )
      )
    )
  )

  (symbol (lib_id "antmicropower:GND") (at 30.48 207.01 0) (unit 1)
    (in_bom yes) (on_board yes) (dnp no)
    (property "Reference" "#PWR0131" (at 30.48 213.36 0)
      (effects (font (size 1.27 1.27)) hide)
    )
    (property "Value" "GND" (at 30.48 210.82 0)
      (effects (font (size 1.27 1.27) (thickness 0.15)))
    )
    (property "Footprint" "" (at 39.37 214.63 0)
      (effects (font (size 1.27 1.27) (thickness 0.15)) (justify left bottom) hide)
    )
    (property "Datasheet" "" (at 39.37 219.71 0)
      (effects (font (size 1.27 1.27) (thickness 0.15)) (justify left bottom) hide)
    )
    (property "Author" "Antmicro" (at 39.37 214.63 0)
      (effects (font (size 1.27 1.27) (thickness 0.15)) (justify left bottom) hide)
    )
    (property "License" "Apache-2.0" (at 39.37 217.17 0)
      (effects (font (size 1.27 1.27) (thickness 0.15)) (justify left bottom) hide)
    )
    (pin "1")
    (instances
      (project "d1600e-psu-breakout-board"
        (path ""
          (reference "#PWR0131") (unit 1)
        )
      )
    )
  )

  (symbol (lib_id "antmicroResistors0603:R_4k7_0603") (at 165.1 250.19 90) (unit 1)
    (in_bom yes) (on_board yes) (dnp no)
    (property "Reference" "R12" (at 166.37 246.38 90)
      (effects (font (size 1.27 1.27)) (justify right))
    )
    (property "Value" "R_4k7_0603" (at 177.8 229.87 0)
      (effects (font (size 1.27 1.27) (thickness 0.15)) (justify left bottom) hide)
    )
    (property "Footprint" "antmicro-footprints:R_0603_1608Metric" (at 180.34 229.87 0)
      (effects (font (size 1.27 1.27) (thickness 0.15)) (justify left bottom) hide)
    )
    (property "Datasheet" "https://www.bourns.com/docs/product-datasheets/cr.pdf" (at 182.88 229.87 0)
      (effects (font (size 1.27 1.27) (thickness 0.15)) (justify left bottom) hide)
    )
    (property "Manufacturer" "Bourns" (at 187.96 229.87 0)
      (effects (font (size 1.27 1.27) (thickness 0.15)) (justify left bottom) hide)
    )
    (property "MPN" "CR0603-FX-4701ELF" (at 185.42 229.87 0)
      (effects (font (size 1.27 1.27) (thickness 0.15)) (justify left bottom) hide)
    )
    (property "Val" "4k7" (at 166.37 248.92 90)
      (effects (font (size 1.27 1.27) (thickness 0.15)) (justify right))
    )
    (property "License" "Apache-2.0" (at 190.5 229.87 0)
      (effects (font (size 1.27 1.27) (thickness 0.15)) (justify left bottom) hide)
    )
    (property "Author" "Antmicro" (at 193.04 229.87 0)
      (effects (font (size 1.27 1.27) (thickness 0.15)) (justify left bottom) hide)
    )
    (property "Tolerance" "1%" (at 175.26 229.87 0)
      (effects (font (size 1.27 1.27)) (justify left bottom) hide)
    )
    (pin "1")
    (pin "2")
    (instances
      (project "d1600e-psu-breakout-board"
        (path ""
          (reference "R12") (unit 1)
        )
      )
    )
  )

  (symbol (lib_name "LED_G_0603_LG_L29K-G2J1-24-Z_6") (lib_id "antmicroLEDIndicationDiscrete:LED_G_0603_LG_L29K-G2J1-24-Z") (at 215.9 257.81 90) (unit 1)
    (in_bom yes) (on_board yes) (dnp no)
    (property "Reference" "D9" (at 217.17 254 90)
      (effects (font (size 1.27 1.27)) (justify right))
    )
    (property "Value" "LED_G_0603_LG_L29K-G2J1-24-Z" (at 223.52 237.49 0)
      (effects (font (size 1.27 1.27) (thickness 0.15)) (justify left bottom) hide)
    )
    (property "Footprint" "antmicro-footprints:LED_0603_1608Metric_G" (at 226.06 237.49 0)
      (effects (font (size 1.27 1.27) (thickness 0.15)) (justify left bottom) hide)
    )
    (property "Datasheet" "https://look.ams-osram.com/m/19ee86b3ae0ee95b/original/LG-L29K.pdf" (at 228.6 237.49 0)
      (effects (font (size 1.27 1.27) (thickness 0.15)) (justify left bottom) hide)
    )
    (property "MPN" "LG L29K-G2J1-24-Z" (at 231.14 237.49 0)
      (effects (font (size 1.27 1.27) (thickness 0.15)) (justify left bottom) hide)
    )
    (property "Manufacturer" "OSRAM" (at 233.68 237.49 0)
      (effects (font (size 1.27 1.27) (thickness 0.15)) (justify left bottom) hide)
    )
    (property "Color" "Green" (at 217.17 256.54 90)
      (effects (font (size 1.27 1.27)) (justify right))
    )
    (property "Author" "Antmicro" (at 236.22 237.49 0)
      (effects (font (size 1.27 1.27) (thickness 0.15)) (justify left bottom) hide)
    )
    (property "License" "Apache-2.0" (at 238.76 237.49 0)
      (effects (font (size 1.27 1.27) (thickness 0.15)) (justify left bottom) hide)
    )
    (pin "1")
    (pin "2")
    (instances
      (project "d1600e-psu-breakout-board"
        (path ""
          (reference "D9") (unit 1)
        )
      )
    )
  )

  (symbol (lib_id "antmicroWire2BoardConnectors:Molex_KK_1x4_22-27-2041") (at 93.98 209.55 0) (mirror x) (unit 1)
    (in_bom yes) (on_board yes) (dnp no)
    (property "Reference" "J12" (at 100.33 207.01 0)
      (effects (font (size 1.27 1.27) (thickness 0.15)) (justify left))
    )
    (property "Value" "Molex_KK_1x4_22-27-2041" (at 107.315 204.47 0)
      (effects (font (size 1.27 1.27) (thickness 0.15)) (justify left bottom) hide)
    )
    (property "Footprint" "antmicro-footprints:Conn_Molex_KK_1x4_22-27-2041" (at 107.315 201.93 0)
      (effects (font (size 1.27 1.27) (thickness 0.15)) (justify left bottom) hide)
    )
    (property "Datasheet" "https://www.molex.com/en-us/products/part-detail/22272041?display=pdf" (at 107.315 199.39 0)
      (effects (font (size 1.27 1.27) (thickness 0.15)) (justify left bottom) hide)
    )
    (property "MPN" "22-27-2041" (at 100.33 204.47 0)
      (effects (font (size 1.27 1.27) (thickness 0.15)) (justify left))
    )
    (property "Manufacturer" "Molex" (at 107.315 194.31 0)
      (effects (font (size 1.27 1.27) (thickness 0.15)) (justify left bottom) hide)
    )
    (property "Author" "Antmicro" (at 107.315 191.77 0)
      (effects (font (size 1.27 1.27) (thickness 0.15)) (justify left bottom) hide)
    )
    (property "License" "Apache-2.0" (at 107.315 189.23 0)
      (effects (font (size 1.27 1.27) (thickness 0.15)) (justify left bottom) hide)
    )
    (pin "3")
    (pin "1")
    (pin "2")
    (pin "4")
    (instances
      (project "d1600e-psu-breakout-board"
        (path ""
          (reference "J12") (unit 1)
        )
      )
    )
  )

  (symbol (lib_id "antmicroSlideSwitches:SW_SPDT_PCM12SMTR") (at 191.77 77.47 0) (unit 1)
    (in_bom yes) (on_board yes) (dnp no)
    (property "Reference" "S1" (at 198.12 69.85 0)
      (effects (font (size 1.27 1.27) (thickness 0.15)))
    )
    (property "Value" "SW_SPDT_PCM12SMTR" (at 198.12 71.12 0)
      (effects (font (size 1.27 1.27) (thickness 0.15)) hide)
    )
    (property "Footprint" "antmicro-footprints:PCM12SMTR" (at 219.71 87.63 0)
      (effects (font (size 1.27 1.27) (thickness 0.15)) (justify left bottom) hide)
    )
    (property "Datasheet" "https://www.mouser.com/datasheet/2/60/pcm-1841544.pdf" (at 219.71 90.17 0)
      (effects (font (size 1.27 1.27) (thickness 0.15)) (justify left bottom) hide)
    )
    (property "Manufacturer" "C&K" (at 219.71 92.71 0)
      (effects (font (size 1.27 1.27) (thickness 0.15)) (justify left bottom) hide)
    )
    (property "MPN" "PCM12SMTR" (at 198.12 72.39 0)
      (effects (font (size 1.27 1.27) (thickness 0.15)))
    )
    (property "Author" "Antmicro" (at 219.71 97.79 0)
      (effects (font (size 1.27 1.27) (thickness 0.15)) (justify left bottom) hide)
    )
    (property "License" "Apache-2.0" (at 219.71 100.33 0)
      (effects (font (size 1.27 1.27) (thickness 0.15)) (justify left bottom) hide)
    )
    (pin "1")
    (pin "2")
    (pin "3")
    (pin "S1")
    (pin "S2")
    (pin "S3")
    (pin "S4")
    (instances
      (project "d1600e-psu-breakout-board"
        (path ""
          (reference "S1") (unit 1)
        )
      )
    )
  )

  (symbol (lib_name "PESD5V0S2BQA_1") (lib_id "antmicroTVSDiodes:PESD5V0S2BQA") (at 39.37 96.52 0) (unit 1)
    (in_bom yes) (on_board yes) (dnp no)
    (property "Reference" "D13" (at 41.91 90.17 0)
      (effects (font (size 1.27 1.27)) (justify left))
    )
    (property "Value" "PESD5V0S2BQA" (at 67.31 106.68 0)
      (effects (font (size 1.27 1.27) (thickness 0.15)) (justify left bottom) hide)
    )
    (property "Footprint" "antmicro-footprints:TPD2E009DRTR" (at 67.31 109.22 0)
      (effects (font (size 1.27 1.27) (thickness 0.15)) (justify left bottom) hide)
    )
    (property "Datasheet" "https://4donline.ihs.com/images/VipMasterIC/IC/NEXP/NEXP-S-A0003105620/NEXP-S-A0003107857-1.pdf?hkey=6D3A4C79FDBF58556ACFDE234799DDF0" (at 67.31 111.76 0)
      (effects (font (size 1.27 1.27) (thickness 0.15)) (justify left bottom) hide)
    )
    (property "MPN" "PESD5V0S2BQA" (at 41.91 92.71 0)
      (effects (font (size 1.27 1.27) (thickness 0.15)) (justify left))
    )
    (property "Manufacturer" "Nexperia" (at 67.31 104.14 0)
      (effects (font (size 1.27 1.27) (thickness 0.15)) (justify left bottom) hide)
    )
    (property "Author" "Antmicro" (at 67.31 114.3 0)
      (effects (font (size 1.27 1.27) (thickness 0.15)) (justify left bottom) hide)
    )
    (property "License" "Apache-2.0" (at 67.31 116.84 0)
      (effects (font (size 1.27 1.27) (thickness 0.15)) (justify left bottom) hide)
    )
    (pin "1")
    (pin "2")
    (pin "3")
    (instances
      (project "d1600e-psu-breakout-board"
        (path ""
          (reference "D13") (unit 1)
        )
      )
    )
  )

  (symbol (lib_name "LED_G_0603_LG_L29K-G2J1-24-Z_7") (lib_id "antmicroLEDIndicationDiscrete:LED_G_0603_LG_L29K-G2J1-24-Z") (at 227.33 257.81 90) (unit 1)
    (in_bom yes) (on_board yes) (dnp no)
    (property "Reference" "D10" (at 228.6 254 90)
      (effects (font (size 1.27 1.27)) (justify right))
    )
    (property "Value" "LED_G_0603_LG_L29K-G2J1-24-Z" (at 234.95 237.49 0)
      (effects (font (size 1.27 1.27) (thickness 0.15)) (justify left bottom) hide)
    )
    (property "Footprint" "antmicro-footprints:LED_0603_1608Metric_G" (at 237.49 237.49 0)
      (effects (font (size 1.27 1.27) (thickness 0.15)) (justify left bottom) hide)
    )
    (property "Datasheet" "https://look.ams-osram.com/m/19ee86b3ae0ee95b/original/LG-L29K.pdf" (at 240.03 237.49 0)
      (effects (font (size 1.27 1.27) (thickness 0.15)) (justify left bottom) hide)
    )
    (property "MPN" "LG L29K-G2J1-24-Z" (at 242.57 237.49 0)
      (effects (font (size 1.27 1.27) (thickness 0.15)) (justify left bottom) hide)
    )
    (property "Manufacturer" "OSRAM" (at 245.11 237.49 0)
      (effects (font (size 1.27 1.27) (thickness 0.15)) (justify left bottom) hide)
    )
    (property "Color" "Green" (at 228.6 256.54 90)
      (effects (font (size 1.27 1.27)) (justify right))
    )
    (property "Author" "Antmicro" (at 247.65 237.49 0)
      (effects (font (size 1.27 1.27) (thickness 0.15)) (justify left bottom) hide)
    )
    (property "License" "Apache-2.0" (at 250.19 237.49 0)
      (effects (font (size 1.27 1.27) (thickness 0.15)) (justify left bottom) hide)
    )
    (pin "1")
    (pin "2")
    (instances
      (project "d1600e-psu-breakout-board"
        (path ""
          (reference "D10") (unit 1)
        )
      )
    )
  )

  (symbol (lib_id "antmicropower:GND") (at 177.8 260.35 0) (unit 1)
    (in_bom yes) (on_board yes) (dnp no)
    (property "Reference" "#PWR07" (at 177.8 266.7 0)
      (effects (font (size 1.27 1.27)) hide)
    )
    (property "Value" "GND" (at 177.8 264.16 0)
      (effects (font (size 1.27 1.27) (thickness 0.15)))
    )
    (property "Footprint" "" (at 186.69 267.97 0)
      (effects (font (size 1.27 1.27) (thickness 0.15)) (justify left bottom) hide)
    )
    (property "Datasheet" "" (at 186.69 273.05 0)
      (effects (font (size 1.27 1.27) (thickness 0.15)) (justify left bottom) hide)
    )
    (property "Author" "Antmicro" (at 186.69 267.97 0)
      (effects (font (size 1.27 1.27) (thickness 0.15)) (justify left bottom) hide)
    )
    (property "License" "Apache-2.0" (at 186.69 270.51 0)
      (effects (font (size 1.27 1.27) (thickness 0.15)) (justify left bottom) hide)
    )
    (pin "1")
    (instances
      (project "d1600e-psu-breakout-board"
        (path ""
          (reference "#PWR07") (unit 1)
        )
      )
    )
  )

  (symbol (lib_id "antmicroTVSDiodes:PESD5V0S2BQA") (at 105.41 96.52 0) (unit 1)
    (in_bom yes) (on_board yes) (dnp no)
    (property "Reference" "D12" (at 107.95 90.17 0)
      (effects (font (size 1.27 1.27)) (justify left))
    )
    (property "Value" "PESD5V0S2BQA" (at 133.35 106.68 0)
      (effects (font (size 1.27 1.27) (thickness 0.15)) (justify left bottom) hide)
    )
    (property "Footprint" "antmicro-footprints:TPD2E009DRTR" (at 133.35 109.22 0)
      (effects (font (size 1.27 1.27) (thickness 0.15)) (justify left bottom) hide)
    )
    (property "Datasheet" "https://4donline.ihs.com/images/VipMasterIC/IC/NEXP/NEXP-S-A0003105620/NEXP-S-A0003107857-1.pdf?hkey=6D3A4C79FDBF58556ACFDE234799DDF0" (at 133.35 111.76 0)
      (effects (font (size 1.27 1.27) (thickness 0.15)) (justify left bottom) hide)
    )
    (property "MPN" "PESD5V0S2BQA" (at 107.95 92.71 0)
      (effects (font (size 1.27 1.27) (thickness 0.15)) (justify left))
    )
    (property "Manufacturer" "Nexperia" (at 133.35 104.14 0)
      (effects (font (size 1.27 1.27) (thickness 0.15)) (justify left bottom) hide)
    )
    (property "Author" "Antmicro" (at 133.35 114.3 0)
      (effects (font (size 1.27 1.27) (thickness 0.15)) (justify left bottom) hide)
    )
    (property "License" "Apache-2.0" (at 133.35 116.84 0)
      (effects (font (size 1.27 1.27) (thickness 0.15)) (justify left bottom) hide)
    )
    (pin "1")
    (pin "2")
    (pin "3")
    (instances
      (project "d1600e-psu-breakout-board"
        (path ""
          (reference "D12") (unit 1)
        )
      )
    )
  )

  (symbol (lib_name "LED_G_0603_LG_L29K-G2J1-24-Z_8") (lib_id "antmicroLEDIndicationDiscrete:LED_G_0603_LG_L29K-G2J1-24-Z") (at 203.2 257.81 90) (unit 1)
    (in_bom yes) (on_board yes) (dnp no)
    (property "Reference" "D8" (at 204.47 254 90)
      (effects (font (size 1.27 1.27)) (justify right))
    )
    (property "Value" "LED_G_0603_LG_L29K-G2J1-24-Z" (at 210.82 237.49 0)
      (effects (font (size 1.27 1.27) (thickness 0.15)) (justify left bottom) hide)
    )
    (property "Footprint" "antmicro-footprints:LED_0603_1608Metric_G" (at 213.36 237.49 0)
      (effects (font (size 1.27 1.27) (thickness 0.15)) (justify left bottom) hide)
    )
    (property "Datasheet" "https://look.ams-osram.com/m/19ee86b3ae0ee95b/original/LG-L29K.pdf" (at 215.9 237.49 0)
      (effects (font (size 1.27 1.27) (thickness 0.15)) (justify left bottom) hide)
    )
    (property "MPN" "LG L29K-G2J1-24-Z" (at 218.44 237.49 0)
      (effects (font (size 1.27 1.27) (thickness 0.15)) (justify left bottom) hide)
    )
    (property "Manufacturer" "OSRAM" (at 220.98 237.49 0)
      (effects (font (size 1.27 1.27) (thickness 0.15)) (justify left bottom) hide)
    )
    (property "Color" "Green" (at 204.47 256.54 90)
      (effects (font (size 1.27 1.27)) (justify right))
    )
    (property "Author" "Antmicro" (at 223.52 237.49 0)
      (effects (font (size 1.27 1.27) (thickness 0.15)) (justify left bottom) hide)
    )
    (property "License" "Apache-2.0" (at 226.06 237.49 0)
      (effects (font (size 1.27 1.27) (thickness 0.15)) (justify left bottom) hide)
    )
    (pin "1")
    (pin "2")
    (instances
      (project "d1600e-psu-breakout-board"
        (path ""
          (reference "D8") (unit 1)
        )
      )
    )
  )

  (symbol (lib_id "antmicropower:GND") (at 77.47 234.95 0) (unit 1)
    (in_bom yes) (on_board yes) (dnp no)
    (property "Reference" "#PWR0134" (at 77.47 241.3 0)
      (effects (font (size 1.27 1.27)) hide)
    )
    (property "Value" "GND" (at 77.47 238.76 0)
      (effects (font (size 1.27 1.27) (thickness 0.15)))
    )
    (property "Footprint" "" (at 86.36 242.57 0)
      (effects (font (size 1.27 1.27) (thickness 0.15)) (justify left bottom) hide)
    )
    (property "Datasheet" "" (at 86.36 247.65 0)
      (effects (font (size 1.27 1.27) (thickness 0.15)) (justify left bottom) hide)
    )
    (property "Author" "Antmicro" (at 86.36 242.57 0)
      (effects (font (size 1.27 1.27) (thickness 0.15)) (justify left bottom) hide)
    )
    (property "License" "Apache-2.0" (at 86.36 245.11 0)
      (effects (font (size 1.27 1.27) (thickness 0.15)) (justify left bottom) hide)
    )
    (pin "1")
    (instances
      (project "d1600e-psu-breakout-board"
        (path ""
          (reference "#PWR0134") (unit 1)
        )
      )
    )
  )

  (symbol (lib_id "antmicropower:GND") (at 36.83 102.87 0) (unit 1)
    (in_bom yes) (on_board yes) (dnp no)
    (property "Reference" "#PWR0128" (at 36.83 109.22 0)
      (effects (font (size 1.27 1.27)) hide)
    )
    (property "Value" "GND" (at 36.83 106.68 0)
      (effects (font (size 1.27 1.27) (thickness 0.15)))
    )
    (property "Footprint" "" (at 45.72 110.49 0)
      (effects (font (size 1.27 1.27) (thickness 0.15)) (justify left bottom) hide)
    )
    (property "Datasheet" "" (at 45.72 115.57 0)
      (effects (font (size 1.27 1.27) (thickness 0.15)) (justify left bottom) hide)
    )
    (property "Author" "Antmicro" (at 45.72 110.49 0)
      (effects (font (size 1.27 1.27) (thickness 0.15)) (justify left bottom) hide)
    )
    (property "License" "Apache-2.0" (at 45.72 113.03 0)
      (effects (font (size 1.27 1.27) (thickness 0.15)) (justify left bottom) hide)
    )
    (pin "1")
    (instances
      (project "d1600e-psu-breakout-board"
        (path ""
          (reference "#PWR0128") (unit 1)
        )
      )
    )
  )

  (symbol (lib_id "antmicroWire2BoardConnectors:Molex_Mini-Fit-Jr_2x4_39-28-8080") (at 83.82 177.8 0) (unit 1)
    (in_bom yes) (on_board yes) (dnp no) (fields_autoplaced)
    (property "Reference" "J6" (at 90.17 171.45 0)
      (effects (font (size 1.27 1.27) (thickness 0.15)))
    )
    (property "Value" "Molex_Mini-Fit-Jr_2x4_39-28-8080" (at 110.49 186.69 0)
      (effects (font (size 1.27 1.27) (thickness 0.15)) (justify left bottom) hide)
    )
    (property "Footprint" "antmicro-footprints:MOLEX_39288080" (at 110.49 189.23 0)
      (effects (font (size 1.27 1.27) (thickness 0.15)) (justify left bottom) hide)
    )
    (property "Datasheet" "https://www.molex.com/pdm_docs/sd/039288080_sd.pdf" (at 110.49 191.77 0)
      (effects (font (size 1.27 1.27) (thickness 0.15)) (justify left bottom) hide)
    )
    (property "MPN" "39-28-8080" (at 90.17 173.99 0)
      (effects (font (size 1.27 1.27) (thickness 0.15)))
    )
    (property "Manufacturer" "Molex" (at 110.49 194.31 0)
      (effects (font (size 1.27 1.27) (thickness 0.15)) (justify left bottom) hide)
    )
    (property "Author" "Antmicro" (at 110.49 196.85 0)
      (effects (font (size 1.27 1.27) (thickness 0.15)) (justify left bottom) hide)
    )
    (property "License" "Apache-2.0" (at 110.49 199.39 0)
      (effects (font (size 1.27 1.27) (thickness 0.15)) (justify left bottom) hide)
    )
    (pin "3")
    (pin "8")
    (pin "6")
    (pin "5")
    (pin "4")
    (pin "2")
    (pin "7")
    (pin "1")
    (instances
      (project "d1600e-psu-breakout-board"
        (path ""
          (reference "J6") (unit 1)
        )
      )
    )
  )

  (symbol (lib_id "antmicroWire2BoardConnectors:Molex_KK_1x4_22-27-2041") (at 93.98 224.79 0) (mirror x) (unit 1)
    (in_bom yes) (on_board yes) (dnp no)
    (property "Reference" "J13" (at 100.33 222.25 0)
      (effects (font (size 1.27 1.27) (thickness 0.15)) (justify left))
    )
    (property "Value" "Molex_KK_1x4_22-27-2041" (at 107.315 219.71 0)
      (effects (font (size 1.27 1.27) (thickness 0.15)) (justify left bottom) hide)
    )
    (property "Footprint" "antmicro-footprints:Conn_Molex_KK_1x4_22-27-2041" (at 107.315 217.17 0)
      (effects (font (size 1.27 1.27) (thickness 0.15)) (justify left bottom) hide)
    )
    (property "Datasheet" "https://www.molex.com/en-us/products/part-detail/22272041?display=pdf" (at 107.315 214.63 0)
      (effects (font (size 1.27 1.27) (thickness 0.15)) (justify left bottom) hide)
    )
    (property "MPN" "22-27-2041" (at 100.33 219.71 0)
      (effects (font (size 1.27 1.27) (thickness 0.15)) (justify left))
    )
    (property "Manufacturer" "Molex" (at 107.315 209.55 0)
      (effects (font (size 1.27 1.27) (thickness 0.15)) (justify left bottom) hide)
    )
    (property "Author" "Antmicro" (at 107.315 207.01 0)
      (effects (font (size 1.27 1.27) (thickness 0.15)) (justify left bottom) hide)
    )
    (property "License" "Apache-2.0" (at 107.315 204.47 0)
      (effects (font (size 1.27 1.27) (thickness 0.15)) (justify left bottom) hide)
    )
    (pin "3")
    (pin "1")
    (pin "2")
    (pin "4")
    (instances
      (project "d1600e-psu-breakout-board"
        (path ""
          (reference "J13") (unit 1)
        )
      )
    )
  )

  (sheet (at 271.78 24.13) (size 115.57 49.53) (fields_autoplaced)
    (stroke (width 0) (type solid))
    (fill (color 0 0 0 0.0000))
    (property "Sheetname" "FTDI" (at 271.78 23.4184 0)
      (effects (font (size 1.27 1.27)) (justify left bottom))
    )
    (property "Sheetfile" "ftdi-module.kicad_sch" (at 271.78 74.2446 0)
      (effects (font (size 1.27 1.27)) (justify left top))
    )
    (instances
      (project "d1600e-psu-breakout-board"
        (path "" (page "2"))
      )
    )
  )

  (sheet (at 271.78 85.09) (size 115.57 45.72) (fields_autoplaced)
    (stroke (width 0) (type solid))
    (fill (color 0 0 0 0.0000))
    (property "Sheetname" "Power Cycling & Current Measurement" (at 271.78 84.3784 0)
      (effects (font (size 1.27 1.27)) (justify left bottom))
    )
    (property "Sheetfile" "pow-cycl-curr-meas.kicad_sch" (at 271.78 131.3946 0)
      (effects (font (size 1.27 1.27)) (justify left top))
    )
    (instances
      (project "d1600e-psu-breakout-board"
        (path "" (page "3"))
      )
    )
  )

  (sheet (at 271.78 143.51) (size 114.3 45.72) (fields_autoplaced)
    (stroke (width 0) (type solid))
    (fill (color 0 0 0 0.0000))
    (property "Sheetname" "daughterboard-supply" (at 271.78 142.7984 0)
      (effects (font (size 1.27 1.27)) (justify left bottom))
    )
    (property "Sheetfile" "daughterboard-supply.kicad_sch" (at 271.78 189.8146 0)
      (effects (font (size 1.27 1.27)) (justify left top))
    )
    (instances
      (project "d1600e-psu-breakout-board"
        (path "" (page "4"))
      )
    )
  )

  (sheet_instances
    (path "/" (page "1"))
  )
)
